FILE_TYPE = MACRO_DRAWING;
SET COLOR_WIRE YELLOW;
SET COLOR_PROP ORANGE;
SET COLOR_DOT WHITE;
SET COLOR_ARC YELLOW;
SET COLOR_BODY GREEN;
SET COLOR_NOTE PURPLE;
SET PROP_DISPLAY VALUE;
SET PAGE_NUMBER P51;
FORCEADD GENOA_SP5..15
(-4700 4750);
FORCEPROP 1 LAST LOCATION U26
J 0
(-5795 6006);
DISPLAY 0.489362 (-5795 6006);
PAINT SKYBLUE (-5795 6006);
FORCEPROP 0 LAST $SEC 15
J 0
(-5775 6050);
DISPLAY 0.680851 (-5775 6050);
PAINT MONO (-5775 6050);
DISPLAY INVISIBLE (-5775 6050);
FORCEPROP 0 LAST CDS_SEC 15
J 0
(-5800 6000);
DISPLAY 1.021277 (-5800 6000);
DISPLAY INVISIBLE (-5800 6000);
FORCEPROP 0 LASTPIN (-5950 5500) $PN BW53
J 2
(-5960 5510);
DISPLAY 0.489362 (-5960 5510);
PAINT MONO (-5960 5510);
FORCEPROP 0 LASTPIN (-5950 5400) $PN CA53
J 2
(-5960 5410);
DISPLAY 0.489362 (-5960 5410);
PAINT MONO (-5960 5410);
FORCEPROP 0 LASTPIN (-5950 5300) $PN BU53
J 2
(-5960 5310);
DISPLAY 0.489362 (-5960 5310);
PAINT MONO (-5960 5310);
FORCEPROP 0 LASTPIN (-5950 5200) $PN BW50
J 2
(-5960 5210);
DISPLAY 0.489362 (-5960 5210);
PAINT MONO (-5960 5210);
FORCEPROP 0 LASTPIN (-5950 5100) $PN CA50
J 2
(-5960 5110);
DISPLAY 0.489362 (-5960 5110);
PAINT MONO (-5960 5110);
FORCEPROP 0 LASTPIN (-5950 5000) $PN BU50
J 2
(-5960 5010);
DISPLAY 0.489362 (-5960 5010);
PAINT MONO (-5960 5010);
FORCEPROP 0 LASTPIN (-5950 4900) $PN BW47
J 2
(-5960 4910);
DISPLAY 0.489362 (-5960 4910);
PAINT MONO (-5960 4910);
FORCEPROP 0 LASTPIN (-5950 4800) $PN CA47
J 2
(-5960 4810);
DISPLAY 0.489362 (-5960 4810);
PAINT MONO (-5960 4810);
FORCEPROP 0 LASTPIN (-5950 4700) $PN BU47
J 2
(-5960 4710);
DISPLAY 0.489362 (-5960 4710);
PAINT MONO (-5960 4710);
FORCEPROP 0 LASTPIN (-5950 4600) $PN BW44
J 2
(-5960 4610);
DISPLAY 0.489362 (-5960 4610);
PAINT MONO (-5960 4610);
FORCEPROP 0 LASTPIN (-5950 4500) $PN CA44
J 2
(-5960 4510);
DISPLAY 0.489362 (-5960 4510);
PAINT MONO (-5960 4510);
FORCEPROP 0 LASTPIN (-5950 4400) $PN BU44
J 2
(-5960 4410);
DISPLAY 0.489362 (-5960 4410);
PAINT MONO (-5960 4410);
FORCEPROP 0 LASTPIN (-5950 4300) $PN BY41
J 2
(-5960 4310);
DISPLAY 0.489362 (-5960 4310);
PAINT MONO (-5960 4310);
FORCEPROP 0 LASTPIN (-5950 4200) $PN CB41
J 2
(-5960 4210);
DISPLAY 0.489362 (-5960 4210);
PAINT MONO (-5960 4210);
FORCEPROP 0 LASTPIN (-5950 4100) $PN BV41
J 2
(-5960 4110);
DISPLAY 0.489362 (-5960 4110);
PAINT MONO (-5960 4110);
FORCEPROP 0 LASTPIN (-5950 4000) $PN BT41
J 2
(-5960 4010);
DISPLAY 0.489362 (-5960 4010);
PAINT MONO (-5960 4010);
FORCEPROP 0 LASTPIN (-5950 5550) $PN BW52
J 2
(-5960 5560);
DISPLAY 0.489362 (-5960 5560);
PAINT MONO (-5960 5560);
FORCEPROP 0 LASTPIN (-5950 5450) $PN CA52
J 2
(-5960 5460);
DISPLAY 0.489362 (-5960 5460);
PAINT MONO (-5960 5460);
FORCEPROP 0 LASTPIN (-5950 5350) $PN BU52
J 2
(-5960 5360);
DISPLAY 0.489362 (-5960 5360);
PAINT MONO (-5960 5360);
FORCEPROP 0 LASTPIN (-5950 5250) $PN BW49
J 2
(-5960 5260);
DISPLAY 0.489362 (-5960 5260);
PAINT MONO (-5960 5260);
FORCEPROP 0 LASTPIN (-5950 5150) $PN CA49
J 2
(-5960 5160);
DISPLAY 0.489362 (-5960 5160);
PAINT MONO (-5960 5160);
FORCEPROP 0 LASTPIN (-5950 5050) $PN BU49
J 2
(-5960 5060);
DISPLAY 0.489362 (-5960 5060);
PAINT MONO (-5960 5060);
FORCEPROP 0 LASTPIN (-5950 4950) $PN BW46
J 2
(-5960 4960);
DISPLAY 0.489362 (-5960 4960);
PAINT MONO (-5960 4960);
FORCEPROP 0 LASTPIN (-5950 4850) $PN CA46
J 2
(-5960 4860);
DISPLAY 0.489362 (-5960 4860);
PAINT MONO (-5960 4860);
FORCEPROP 0 LASTPIN (-5950 4750) $PN BU46
J 2
(-5960 4760);
DISPLAY 0.489362 (-5960 4760);
PAINT MONO (-5960 4760);
FORCEPROP 0 LASTPIN (-5950 4650) $PN BW43
J 2
(-5960 4660);
DISPLAY 0.489362 (-5960 4660);
PAINT MONO (-5960 4660);
FORCEPROP 0 LASTPIN (-5950 4550) $PN CA43
J 2
(-5960 4560);
DISPLAY 0.489362 (-5960 4560);
PAINT MONO (-5960 4560);
FORCEPROP 0 LASTPIN (-5950 4450) $PN BU43
J 2
(-5960 4460);
DISPLAY 0.489362 (-5960 4460);
PAINT MONO (-5960 4460);
FORCEPROP 0 LASTPIN (-5950 4350) $PN BY40
J 2
(-5960 4360);
DISPLAY 0.489362 (-5960 4360);
PAINT MONO (-5960 4360);
FORCEPROP 0 LASTPIN (-5950 4250) $PN CB40
J 2
(-5960 4260);
DISPLAY 0.489362 (-5960 4260);
PAINT MONO (-5960 4260);
FORCEPROP 0 LASTPIN (-5950 4150) $PN BV40
J 2
(-5960 4160);
DISPLAY 0.489362 (-5960 4160);
PAINT MONO (-5960 4160);
FORCEPROP 0 LASTPIN (-5950 4050) $PN BT40
J 2
(-5960 4060);
DISPLAY 0.489362 (-5960 4060);
PAINT MONO (-5960 4060);
FORCEPROP 0 LASTPIN (-3450 5500) $PN CN52
J 0
(-3440 5510);
DISPLAY 0.489362 (-3440 5510);
PAINT MONO (-3440 5510);
FORCEPROP 0 LASTPIN (-3450 5400) $PN CR52
J 0
(-3440 5410);
DISPLAY 0.489362 (-3440 5410);
PAINT MONO (-3440 5410);
FORCEPROP 0 LASTPIN (-3450 5300) $PN CL52
J 0
(-3440 5310);
DISPLAY 0.489362 (-3440 5310);
PAINT MONO (-3440 5310);
FORCEPROP 0 LASTPIN (-3450 5200) $PN CN49
J 0
(-3440 5210);
DISPLAY 0.489362 (-3440 5210);
PAINT MONO (-3440 5210);
FORCEPROP 0 LASTPIN (-3450 5100) $PN CR49
J 0
(-3440 5110);
DISPLAY 0.489362 (-3440 5110);
PAINT MONO (-3440 5110);
FORCEPROP 0 LASTPIN (-3450 5000) $PN CU49
J 0
(-3440 5010);
DISPLAY 0.489362 (-3440 5010);
PAINT MONO (-3440 5010);
FORCEPROP 0 LASTPIN (-3450 4900) $PN CL49
J 0
(-3440 4910);
DISPLAY 0.489362 (-3440 4910);
PAINT MONO (-3440 4910);
FORCEPROP 0 LASTPIN (-3450 4800) $PN CR46
J 0
(-3440 4810);
DISPLAY 0.489362 (-3440 4810);
PAINT MONO (-3440 4810);
FORCEPROP 0 LASTPIN (-3450 4700) $PN CU46
J 0
(-3440 4710);
DISPLAY 0.489362 (-3440 4710);
PAINT MONO (-3440 4710);
FORCEPROP 0 LASTPIN (-3450 4600) $PN CN46
J 0
(-3440 4610);
DISPLAY 0.489362 (-3440 4610);
PAINT MONO (-3440 4610);
FORCEPROP 0 LASTPIN (-3450 4500) $PN CR43
J 0
(-3440 4510);
DISPLAY 0.489362 (-3440 4510);
PAINT MONO (-3440 4510);
FORCEPROP 0 LASTPIN (-3450 4400) $PN CU43
J 0
(-3440 4410);
DISPLAY 0.489362 (-3440 4410);
PAINT MONO (-3440 4410);
FORCEPROP 0 LASTPIN (-3450 4300) $PN CN43
J 0
(-3440 4310);
DISPLAY 0.489362 (-3440 4310);
PAINT MONO (-3440 4310);
FORCEPROP 0 LASTPIN (-3450 4200) $PN CT40
J 0
(-3440 4210);
DISPLAY 0.489362 (-3440 4210);
PAINT MONO (-3440 4210);
FORCEPROP 0 LASTPIN (-3450 4100) $PN CP40
J 0
(-3440 4110);
DISPLAY 0.489362 (-3440 4110);
PAINT MONO (-3440 4110);
FORCEPROP 0 LASTPIN (-3450 4000) $PN CM40
J 0
(-3440 4010);
DISPLAY 0.489362 (-3440 4010);
PAINT MONO (-3440 4010);
FORCEPROP 0 LASTPIN (-3450 5550) $PN CN53
J 0
(-3440 5560);
DISPLAY 0.489362 (-3440 5560);
PAINT MONO (-3440 5560);
FORCEPROP 0 LASTPIN (-3450 5450) $PN CR53
J 0
(-3440 5460);
DISPLAY 0.489362 (-3440 5460);
PAINT MONO (-3440 5460);
FORCEPROP 0 LASTPIN (-3450 5350) $PN CL53
J 0
(-3440 5360);
DISPLAY 0.489362 (-3440 5360);
PAINT MONO (-3440 5360);
FORCEPROP 0 LASTPIN (-3450 5250) $PN CN50
J 0
(-3440 5260);
DISPLAY 0.489362 (-3440 5260);
PAINT MONO (-3440 5260);
FORCEPROP 0 LASTPIN (-3450 5150) $PN CR50
J 0
(-3440 5160);
DISPLAY 0.489362 (-3440 5160);
PAINT MONO (-3440 5160);
FORCEPROP 0 LASTPIN (-3450 5050) $PN CU50
J 0
(-3440 5060);
DISPLAY 0.489362 (-3440 5060);
PAINT MONO (-3440 5060);
FORCEPROP 0 LASTPIN (-3450 4950) $PN CL50
J 0
(-3440 4960);
DISPLAY 0.489362 (-3440 4960);
PAINT MONO (-3440 4960);
FORCEPROP 0 LASTPIN (-3450 4850) $PN CR47
J 0
(-3440 4860);
DISPLAY 0.489362 (-3440 4860);
PAINT MONO (-3440 4860);
FORCEPROP 0 LASTPIN (-3450 4750) $PN CU47
J 0
(-3440 4760);
DISPLAY 0.489362 (-3440 4760);
PAINT MONO (-3440 4760);
FORCEPROP 0 LASTPIN (-3450 4650) $PN CN47
J 0
(-3440 4660);
DISPLAY 0.489362 (-3440 4660);
PAINT MONO (-3440 4660);
FORCEPROP 0 LASTPIN (-3450 4550) $PN CR44
J 0
(-3440 4560);
DISPLAY 0.489362 (-3440 4560);
PAINT MONO (-3440 4560);
FORCEPROP 0 LASTPIN (-3450 4450) $PN CU44
J 0
(-3440 4460);
DISPLAY 0.489362 (-3440 4460);
PAINT MONO (-3440 4460);
FORCEPROP 0 LASTPIN (-3450 4350) $PN CN44
J 0
(-3440 4360);
DISPLAY 0.489362 (-3440 4360);
PAINT MONO (-3440 4360);
FORCEPROP 0 LASTPIN (-3450 4250) $PN CT41
J 0
(-3440 4260);
DISPLAY 0.489362 (-3440 4260);
PAINT MONO (-3440 4260);
FORCEPROP 0 LASTPIN (-3450 4150) $PN CP41
J 0
(-3440 4160);
DISPLAY 0.489362 (-3440 4160);
PAINT MONO (-3440 4160);
FORCEPROP 0 LASTPIN (-3450 4050) $PN CM41
J 0
(-3440 4060);
DISPLAY 0.489362 (-3440 4060);
PAINT MONO (-3440 4060);
FORCEPROP 1 LAST MATERIAL IO
J 0
(-5795 5732);
DISPLAY 0.489362 (-5795 5732);
PAINT SKYBLUE (-5795 5732);
FORCEPROP 1 LAST PART_NUMBER DGA^6000030
J 0
(-5795 5859);
DISPLAY 0.489362 (-5795 5859);
PAINT SKYBLUE (-5795 5859);
FORCEPROP 2 LAST PART_TYPE SMLF
J 0
(-5800 5928);
DISPLAY 1.021277 (-5800 5928);
FORCEPROP 2 LAST VALUE SOCKET6096_13568-001
J 0
(-5800 5828);
DISPLAY 0.489362 (-5800 5828);
PAINT SKYBLUE (-5800 5828);
FORCEPROP 2 LAST CDS_LIB pure_quanta
J 0
(-4700 4750);
DISPLAY INVISIBLE (-4700 4750);
FORCEPROP 1 LAST NEEDS_NO_SIZE TRUE
J 0
(-4700 4750);
DISPLAY 0.723404 (-4700 4750);
PAINT GREEN (-4700 4750);
DISPLAY INVISIBLE (-4700 4750);
FORCEPROP 1 LAST CDS_LMAN_SYM_OUTLINE -1100,950,1100,-950
J 0
(-4700 4750);
DISPLAY 0.468085 (-4700 4750);
PAINT GREEN (-4700 4750);
DISPLAY INVISIBLE (-4700 4750);
FORCEPROP 1 LAST PATH I147
J 0
(-4700 4750);
DISPLAY 0.723404 (-4700 4750);
PAINT GREEN (-4700 4750);
DISPLAY INVISIBLE (-4700 4750);
FORCEADD GENOA_SP5..16
(-4700 2100);
FORCEPROP 1 LAST LOCATION U26
J 0
(-5800 3225);
DISPLAY 0.489362 (-5800 3225);
PAINT SKYBLUE (-5800 3225);
FORCEPROP 0 LAST $SEC 16
J 0
(-5775 3400);
DISPLAY 0.680851 (-5775 3400);
PAINT MONO (-5775 3400);
DISPLAY INVISIBLE (-5775 3400);
FORCEPROP 0 LAST CDS_SEC 16
J 0
(-5800 3250);
DISPLAY 1.021277 (-5800 3250);
DISPLAY INVISIBLE (-5800 3250);
FORCEPROP 0 LASTPIN (-5950 2850) $PN CE53
J 2
(-5960 2860);
DISPLAY 0.489362 (-5960 2860);
PAINT MONO (-5960 2860);
FORCEPROP 0 LASTPIN (-5950 2750) $PN CG53
J 2
(-5960 2760);
DISPLAY 0.489362 (-5960 2760);
PAINT MONO (-5960 2760);
FORCEPROP 0 LASTPIN (-5950 2650) $PN CC53
J 2
(-5960 2660);
DISPLAY 0.489362 (-5960 2660);
PAINT MONO (-5960 2660);
FORCEPROP 0 LASTPIN (-5950 2550) $PN CE50
J 2
(-5960 2560);
DISPLAY 0.489362 (-5960 2560);
PAINT MONO (-5960 2560);
FORCEPROP 0 LASTPIN (-5950 2450) $PN CG50
J 2
(-5960 2460);
DISPLAY 0.489362 (-5960 2460);
PAINT MONO (-5960 2460);
FORCEPROP 0 LASTPIN (-5950 2350) $PN CC50
J 2
(-5960 2360);
DISPLAY 0.489362 (-5960 2360);
PAINT MONO (-5960 2360);
FORCEPROP 0 LASTPIN (-5950 2250) $PN CE47
J 2
(-5960 2260);
DISPLAY 0.489362 (-5960 2260);
PAINT MONO (-5960 2260);
FORCEPROP 0 LASTPIN (-5950 2150) $PN CG47
J 2
(-5960 2160);
DISPLAY 0.489362 (-5960 2160);
PAINT MONO (-5960 2160);
FORCEPROP 0 LASTPIN (-5950 2050) $PN CC47
J 2
(-5960 2060);
DISPLAY 0.489362 (-5960 2060);
PAINT MONO (-5960 2060);
FORCEPROP 0 LASTPIN (-5950 1950) $PN CE44
J 2
(-5960 1960);
DISPLAY 0.489362 (-5960 1960);
PAINT MONO (-5960 1960);
FORCEPROP 0 LASTPIN (-5950 1850) $PN CG44
J 2
(-5960 1860);
DISPLAY 0.489362 (-5960 1860);
PAINT MONO (-5960 1860);
FORCEPROP 0 LASTPIN (-5950 1750) $PN CJ44
J 2
(-5960 1760);
DISPLAY 0.489362 (-5960 1760);
PAINT MONO (-5960 1760);
FORCEPROP 0 LASTPIN (-5950 1650) $PN CC44
J 2
(-5960 1660);
DISPLAY 0.489362 (-5960 1660);
PAINT MONO (-5960 1660);
FORCEPROP 0 LASTPIN (-5950 1550) $PN CH41
J 2
(-5960 1560);
DISPLAY 0.489362 (-5960 1560);
PAINT MONO (-5960 1560);
FORCEPROP 0 LASTPIN (-5950 1450) $PN CF41
J 2
(-5960 1460);
DISPLAY 0.489362 (-5960 1460);
PAINT MONO (-5960 1460);
FORCEPROP 0 LASTPIN (-5950 1350) $PN CD41
J 2
(-5960 1360);
DISPLAY 0.489362 (-5960 1360);
PAINT MONO (-5960 1360);
FORCEPROP 0 LASTPIN (-5950 2900) $PN CE52
J 2
(-5960 2910);
DISPLAY 0.489362 (-5960 2910);
PAINT MONO (-5960 2910);
FORCEPROP 0 LASTPIN (-5950 2800) $PN CG52
J 2
(-5960 2810);
DISPLAY 0.489362 (-5960 2810);
PAINT MONO (-5960 2810);
FORCEPROP 0 LASTPIN (-5950 2700) $PN CC52
J 2
(-5960 2710);
DISPLAY 0.489362 (-5960 2710);
PAINT MONO (-5960 2710);
FORCEPROP 0 LASTPIN (-5950 2600) $PN CE49
J 2
(-5960 2610);
DISPLAY 0.489362 (-5960 2610);
PAINT MONO (-5960 2610);
FORCEPROP 0 LASTPIN (-5950 2500) $PN CG49
J 2
(-5960 2510);
DISPLAY 0.489362 (-5960 2510);
PAINT MONO (-5960 2510);
FORCEPROP 0 LASTPIN (-5950 2400) $PN CC49
J 2
(-5960 2410);
DISPLAY 0.489362 (-5960 2410);
PAINT MONO (-5960 2410);
FORCEPROP 0 LASTPIN (-5950 2300) $PN CE46
J 2
(-5960 2310);
DISPLAY 0.489362 (-5960 2310);
PAINT MONO (-5960 2310);
FORCEPROP 0 LASTPIN (-5950 2200) $PN CG46
J 2
(-5960 2210);
DISPLAY 0.489362 (-5960 2210);
PAINT MONO (-5960 2210);
FORCEPROP 0 LASTPIN (-5950 2100) $PN CC46
J 2
(-5960 2110);
DISPLAY 0.489362 (-5960 2110);
PAINT MONO (-5960 2110);
FORCEPROP 0 LASTPIN (-5950 2000) $PN CE43
J 2
(-5960 2010);
DISPLAY 0.489362 (-5960 2010);
PAINT MONO (-5960 2010);
FORCEPROP 0 LASTPIN (-5950 1900) $PN CG43
J 2
(-5960 1910);
DISPLAY 0.489362 (-5960 1910);
PAINT MONO (-5960 1910);
FORCEPROP 0 LASTPIN (-5950 1800) $PN CJ43
J 2
(-5960 1810);
DISPLAY 0.489362 (-5960 1810);
PAINT MONO (-5960 1810);
FORCEPROP 0 LASTPIN (-5950 1700) $PN CC43
J 2
(-5960 1710);
DISPLAY 0.489362 (-5960 1710);
PAINT MONO (-5960 1710);
FORCEPROP 0 LASTPIN (-5950 1600) $PN CH40
J 2
(-5960 1610);
DISPLAY 0.489362 (-5960 1610);
PAINT MONO (-5960 1610);
FORCEPROP 0 LASTPIN (-5950 1500) $PN CF40
J 2
(-5960 1510);
DISPLAY 0.489362 (-5960 1510);
PAINT MONO (-5960 1510);
FORCEPROP 0 LASTPIN (-5950 1400) $PN CD40
J 2
(-5960 1410);
DISPLAY 0.489362 (-5960 1410);
PAINT MONO (-5960 1410);
FORCEPROP 0 LASTPIN (-3450 2850) $PN CU52
J 0
(-3440 2860);
DISPLAY 0.489362 (-3440 2860);
PAINT MONO (-3440 2860);
FORCEPROP 0 LASTPIN (-3450 2750) $PN DA52
J 0
(-3440 2760);
DISPLAY 0.489362 (-3440 2760);
PAINT MONO (-3440 2760);
FORCEPROP 0 LASTPIN (-3450 2650) $PN DC52
J 0
(-3440 2660);
DISPLAY 0.489362 (-3440 2660);
PAINT MONO (-3440 2660);
FORCEPROP 0 LASTPIN (-3450 2550) $PN CW52
J 0
(-3440 2560);
DISPLAY 0.489362 (-3440 2560);
PAINT MONO (-3440 2560);
FORCEPROP 0 LASTPIN (-3450 2450) $PN DA49
J 0
(-3440 2460);
DISPLAY 0.489362 (-3440 2460);
PAINT MONO (-3440 2460);
FORCEPROP 0 LASTPIN (-3450 2350) $PN DC49
J 0
(-3440 2360);
DISPLAY 0.489362 (-3440 2360);
PAINT MONO (-3440 2360);
FORCEPROP 0 LASTPIN (-3450 2250) $PN CW49
J 0
(-3440 2260);
DISPLAY 0.489362 (-3440 2260);
PAINT MONO (-3440 2260);
FORCEPROP 0 LASTPIN (-3450 2150) $PN DA46
J 0
(-3440 2160);
DISPLAY 0.489362 (-3440 2160);
PAINT MONO (-3440 2160);
FORCEPROP 0 LASTPIN (-3450 2050) $PN DC46
J 0
(-3440 2060);
DISPLAY 0.489362 (-3440 2060);
PAINT MONO (-3440 2060);
FORCEPROP 0 LASTPIN (-3450 1950) $PN CW46
J 0
(-3440 1960);
DISPLAY 0.489362 (-3440 1960);
PAINT MONO (-3440 1960);
FORCEPROP 0 LASTPIN (-3450 1850) $PN DA43
J 0
(-3440 1860);
DISPLAY 0.489362 (-3440 1860);
PAINT MONO (-3440 1860);
FORCEPROP 0 LASTPIN (-3450 1750) $PN DC43
J 0
(-3440 1760);
DISPLAY 0.489362 (-3440 1760);
PAINT MONO (-3440 1760);
FORCEPROP 0 LASTPIN (-3450 1650) $PN CW43
J 0
(-3440 1660);
DISPLAY 0.489362 (-3440 1660);
PAINT MONO (-3440 1660);
FORCEPROP 0 LASTPIN (-3450 1550) $PN DB40
J 0
(-3440 1560);
DISPLAY 0.489362 (-3440 1560);
PAINT MONO (-3440 1560);
FORCEPROP 0 LASTPIN (-3450 1450) $PN CY40
J 0
(-3440 1460);
DISPLAY 0.489362 (-3440 1460);
PAINT MONO (-3440 1460);
FORCEPROP 0 LASTPIN (-3450 1350) $PN CV40
J 0
(-3440 1360);
DISPLAY 0.489362 (-3440 1360);
PAINT MONO (-3440 1360);
FORCEPROP 0 LASTPIN (-3450 2900) $PN CU53
J 0
(-3440 2910);
DISPLAY 0.489362 (-3440 2910);
PAINT MONO (-3440 2910);
FORCEPROP 0 LASTPIN (-3450 2800) $PN DA53
J 0
(-3440 2810);
DISPLAY 0.489362 (-3440 2810);
PAINT MONO (-3440 2810);
FORCEPROP 0 LASTPIN (-3450 2700) $PN DC53
J 0
(-3440 2710);
DISPLAY 0.489362 (-3440 2710);
PAINT MONO (-3440 2710);
FORCEPROP 0 LASTPIN (-3450 2600) $PN CW53
J 0
(-3440 2610);
DISPLAY 0.489362 (-3440 2610);
PAINT MONO (-3440 2610);
FORCEPROP 0 LASTPIN (-3450 2500) $PN DA50
J 0
(-3440 2510);
DISPLAY 0.489362 (-3440 2510);
PAINT MONO (-3440 2510);
FORCEPROP 0 LASTPIN (-3450 2400) $PN DC50
J 0
(-3440 2410);
DISPLAY 0.489362 (-3440 2410);
PAINT MONO (-3440 2410);
FORCEPROP 0 LASTPIN (-3450 2300) $PN CW50
J 0
(-3440 2310);
DISPLAY 0.489362 (-3440 2310);
PAINT MONO (-3440 2310);
FORCEPROP 0 LASTPIN (-3450 2200) $PN DA47
J 0
(-3440 2210);
DISPLAY 0.489362 (-3440 2210);
PAINT MONO (-3440 2210);
FORCEPROP 0 LASTPIN (-3450 2100) $PN DC47
J 0
(-3440 2110);
DISPLAY 0.489362 (-3440 2110);
PAINT MONO (-3440 2110);
FORCEPROP 0 LASTPIN (-3450 2000) $PN CW47
J 0
(-3440 2010);
DISPLAY 0.489362 (-3440 2010);
PAINT MONO (-3440 2010);
FORCEPROP 0 LASTPIN (-3450 1900) $PN DA44
J 0
(-3440 1910);
DISPLAY 0.489362 (-3440 1910);
PAINT MONO (-3440 1910);
FORCEPROP 0 LASTPIN (-3450 1800) $PN DC44
J 0
(-3440 1810);
DISPLAY 0.489362 (-3440 1810);
PAINT MONO (-3440 1810);
FORCEPROP 0 LASTPIN (-3450 1700) $PN CW44
J 0
(-3440 1710);
DISPLAY 0.489362 (-3440 1710);
PAINT MONO (-3440 1710);
FORCEPROP 0 LASTPIN (-3450 1600) $PN DB41
J 0
(-3440 1610);
DISPLAY 0.489362 (-3440 1610);
PAINT MONO (-3440 1610);
FORCEPROP 0 LASTPIN (-3450 1500) $PN CY41
J 0
(-3440 1510);
DISPLAY 0.489362 (-3440 1510);
PAINT MONO (-3440 1510);
FORCEPROP 0 LASTPIN (-3450 1400) $PN CV41
J 0
(-3440 1410);
DISPLAY 0.489362 (-3440 1410);
PAINT MONO (-3440 1410);
FORCEPROP 1 LAST MATERIAL IO
J 0
(-5800 3075);
DISPLAY 0.489362 (-5800 3075);
PAINT SKYBLUE (-5800 3075);
FORCEPROP 2 LAST VALUE SOCKET6096_13568-001
J 0
(-5800 3125);
DISPLAY 0.489362 (-5800 3125);
PAINT SKYBLUE (-5800 3125);
FORCEPROP 1 LAST PART_NUMBER DGA^6000030
J 0
(-5800 3150);
DISPLAY 0.489362 (-5800 3150);
PAINT SKYBLUE (-5800 3150);
FORCEPROP 2 LAST PART_TYPE SMLF
J 0
(-5800 3175);
DISPLAY 1.021277 (-5800 3175);
FORCEPROP 1 LAST NEEDS_NO_SIZE TRUE
J 0
(-4700 2100);
DISPLAY 0.723404 (-4700 2100);
PAINT GREEN (-4700 2100);
DISPLAY INVISIBLE (-4700 2100);
FORCEPROP 1 LAST CDS_LMAN_SYM_OUTLINE -1100,950,1100,-950
J 0
(-4700 2100);
DISPLAY 0.468085 (-4700 2100);
PAINT GREEN (-4700 2100);
DISPLAY INVISIBLE (-4700 2100);
FORCEPROP 2 LAST CDS_LIB pure_quanta
J 0
(-4700 2100);
DISPLAY INVISIBLE (-4700 2100);
FORCEPROP 1 LAST PATH I148
J 0
(-4700 2100);
DISPLAY 0.723404 (-4700 2100);
PAINT GREEN (-4700 2100);
DISPLAY INVISIBLE (-4700 2100);
FORCEADD OFFPAGE..2
(-1900 3075);
FORCEPROP 2 LAST $XR0 65 
J 0
(-1711 3075);
DISPLAY 0.638298 (-1711 3075);
PAINT MONO (-1711 3075);
FORCEPROP 2 LAST CDS_LIB standard
J 0
(-1900 3075);
DISPLAY INVISIBLE (-1900 3075);
FORCEPROP 1 LAST OFFPAGE TRUE
J 0
(-1575 2950);
DISPLAY 0.872340 (-1575 2950);
PAINT GREEN (-1575 2950);
DISPLAY INVISIBLE (-1575 2950);
FORCEPROP 1 LAST COMMENT_BODY TRUE
J 0
(-1945 2980);
DISPLAY 0.872340 (-1945 2980);
PAINT GREEN (-1945 2980);
DISPLAY INVISIBLE (-1945 2980);
FORCEPROP 2 LAST PATH I183
J 0
(-1700 3125);
DISPLAY 1.021277 (-1700 3125);
DISPLAY INVISIBLE (-1700 3125);
FORCEADD OFFPAGE..2
(-1900 3125);
FORCEPROP 2 LAST $XR0 65 
J 0
(-1711 3125);
DISPLAY 0.638298 (-1711 3125);
PAINT MONO (-1711 3125);
FORCEPROP 2 LAST CDS_LIB standard
J 0
(-1900 3125);
DISPLAY INVISIBLE (-1900 3125);
FORCEPROP 1 LAST OFFPAGE TRUE
J 0
(-1575 3000);
DISPLAY 0.872340 (-1575 3000);
PAINT GREEN (-1575 3000);
DISPLAY INVISIBLE (-1575 3000);
FORCEPROP 1 LAST COMMENT_BODY TRUE
J 0
(-1945 3030);
DISPLAY 0.872340 (-1945 3030);
PAINT GREEN (-1945 3030);
DISPLAY INVISIBLE (-1945 3030);
FORCEPROP 2 LAST PATH I184
J 0
(-1700 3175);
DISPLAY 1.021277 (-1700 3175);
DISPLAY INVISIBLE (-1700 3175);
FORCEADD TAP..6
R 2
(-2875 2850);
FORCEPROP 3 LASTPIN (-2925 2850) SIG_NAME P5E_CPU1_P1_TX_DN<0>
J 0
(-2915 2860);
DISPLAY 0.659574 (-2915 2860);
PAINT MONO (-2915 2860);
DISPLAY INVISIBLE (-2915 2860);
FORCEPROP 1 LASTPIN (-2925 2850) BN 0
J 2
(-2873 2858);
DISPLAY 0.489362 (-2873 2858);
PAINT MONO (-2873 2858);
FORCEPROP 2 LAST CDS_LIB mstr_standard
J 0
(-2875 2850);
DISPLAY INVISIBLE (-2875 2850);
FORCEPROP 2 LAST BOM_COST IO_SLOT
J 0
(-3375 2950);
DISPLAY 0.829787 (-3375 2950);
DISPLAY INVISIBLE (-3375 2950);
FORCEPROP 1 LAST BODY_TYPE PLUMBING
J 2
(-2875 2800);
DISPLAY 0.702128 (-2875 2800);
PAINT GREEN (-2875 2800);
DISPLAY INVISIBLE (-2875 2800);
FORCEPROP 1 LAST HDL_TAP TRUE
J 2
(-3200 2725);
DISPLAY 0.702128 (-3200 2725);
PAINT GREEN (-3200 2725);
DISPLAY INVISIBLE (-3200 2725);
FORCEPROP 1 LAST PATH I186
J 2
(-2873 2850);
DISPLAY 0.872340 (-2873 2850);
PAINT GREEN (-2873 2850);
DISPLAY INVISIBLE (-2873 2850);
FORCEPROP 2 LAST ROOM RISER1
J 0
(-3375 2900);
DISPLAY 0.829787 (-3375 2900);
PAINT RED (-3375 2900);
DISPLAY INVISIBLE (-3375 2900);
FORCEADD TAP..6
R 2
(-2875 2750);
FORCEPROP 3 LASTPIN (-2925 2750) SIG_NAME P5E_CPU1_P1_TX_DN<1>
J 0
(-2915 2760);
DISPLAY 0.659574 (-2915 2760);
PAINT MONO (-2915 2760);
DISPLAY INVISIBLE (-2915 2760);
FORCEPROP 1 LASTPIN (-2925 2750) BN 1
J 2
(-2873 2758);
DISPLAY 0.489362 (-2873 2758);
PAINT MONO (-2873 2758);
FORCEPROP 2 LAST BOM_COST IO_SLOT
J 0
(-3375 2850);
DISPLAY 0.829787 (-3375 2850);
DISPLAY INVISIBLE (-3375 2850);
FORCEPROP 2 LAST CDS_LIB mstr_standard
J 0
(-2875 2750);
DISPLAY INVISIBLE (-2875 2750);
FORCEPROP 1 LAST BODY_TYPE PLUMBING
J 2
(-2875 2700);
DISPLAY 0.702128 (-2875 2700);
PAINT GREEN (-2875 2700);
DISPLAY INVISIBLE (-2875 2700);
FORCEPROP 1 LAST HDL_TAP TRUE
J 2
(-3200 2625);
DISPLAY 0.702128 (-3200 2625);
PAINT GREEN (-3200 2625);
DISPLAY INVISIBLE (-3200 2625);
FORCEPROP 1 LAST PATH I187
J 2
(-2873 2750);
DISPLAY 0.872340 (-2873 2750);
PAINT GREEN (-2873 2750);
DISPLAY INVISIBLE (-2873 2750);
FORCEPROP 2 LAST ROOM RISER1
J 0
(-3375 2800);
DISPLAY 0.829787 (-3375 2800);
PAINT RED (-3375 2800);
DISPLAY INVISIBLE (-3375 2800);
FORCEADD TAP..6
R 2
(-2875 2650);
FORCEPROP 3 LASTPIN (-2925 2650) SIG_NAME P5E_CPU1_P1_TX_DN<2>
J 0
(-2915 2660);
DISPLAY 0.659574 (-2915 2660);
PAINT MONO (-2915 2660);
DISPLAY INVISIBLE (-2915 2660);
FORCEPROP 1 LASTPIN (-2925 2650) BN 2
J 2
(-2873 2658);
DISPLAY 0.489362 (-2873 2658);
PAINT MONO (-2873 2658);
FORCEPROP 2 LAST BOM_COST IO_SLOT
J 0
(-3375 2750);
DISPLAY 0.829787 (-3375 2750);
DISPLAY INVISIBLE (-3375 2750);
FORCEPROP 2 LAST CDS_LIB standard
J 0
(-2875 2650);
DISPLAY INVISIBLE (-2875 2650);
FORCEPROP 1 LAST BODY_TYPE PLUMBING
J 2
(-2875 2600);
DISPLAY 0.702128 (-2875 2600);
PAINT GREEN (-2875 2600);
DISPLAY INVISIBLE (-2875 2600);
FORCEPROP 1 LAST HDL_TAP TRUE
J 2
(-3200 2525);
DISPLAY 0.702128 (-3200 2525);
PAINT GREEN (-3200 2525);
DISPLAY INVISIBLE (-3200 2525);
FORCEPROP 1 LAST PATH I188
J 2
(-2873 2650);
DISPLAY 0.872340 (-2873 2650);
PAINT GREEN (-2873 2650);
DISPLAY INVISIBLE (-2873 2650);
FORCEPROP 2 LAST ROOM RISER1
J 0
(-3375 2700);
DISPLAY 0.829787 (-3375 2700);
PAINT RED (-3375 2700);
DISPLAY INVISIBLE (-3375 2700);
FORCEADD TAP..6
R 2
(-2875 2450);
FORCEPROP 3 LASTPIN (-2925 2450) SIG_NAME P5E_CPU1_P1_TX_DN<4>
J 0
(-2915 2460);
DISPLAY 0.659574 (-2915 2460);
PAINT MONO (-2915 2460);
DISPLAY INVISIBLE (-2915 2460);
FORCEPROP 1 LASTPIN (-2925 2450) BN 4
J 2
(-2873 2458);
DISPLAY 0.489362 (-2873 2458);
PAINT MONO (-2873 2458);
FORCEPROP 2 LAST BOM_COST IO_SLOT
J 0
(-3375 2550);
DISPLAY 0.829787 (-3375 2550);
DISPLAY INVISIBLE (-3375 2550);
FORCEPROP 2 LAST CDS_LIB standard
J 0
(-2875 2450);
DISPLAY INVISIBLE (-2875 2450);
FORCEPROP 1 LAST BODY_TYPE PLUMBING
J 2
(-2875 2400);
DISPLAY 0.702128 (-2875 2400);
PAINT GREEN (-2875 2400);
DISPLAY INVISIBLE (-2875 2400);
FORCEPROP 1 LAST HDL_TAP TRUE
J 2
(-3200 2325);
DISPLAY 0.702128 (-3200 2325);
PAINT GREEN (-3200 2325);
DISPLAY INVISIBLE (-3200 2325);
FORCEPROP 1 LAST PATH I189
J 2
(-2873 2450);
DISPLAY 0.872340 (-2873 2450);
PAINT GREEN (-2873 2450);
DISPLAY INVISIBLE (-2873 2450);
FORCEPROP 2 LAST ROOM RISER1
J 0
(-3375 2500);
DISPLAY 0.829787 (-3375 2500);
PAINT RED (-3375 2500);
DISPLAY INVISIBLE (-3375 2500);
FORCEADD TAP..6
R 2
(-2875 2550);
FORCEPROP 3 LASTPIN (-2925 2550) SIG_NAME P5E_CPU1_P1_TX_DN<3>
J 0
(-2915 2560);
DISPLAY 0.659574 (-2915 2560);
PAINT MONO (-2915 2560);
DISPLAY INVISIBLE (-2915 2560);
FORCEPROP 1 LASTPIN (-2925 2550) BN 3
J 2
(-2873 2558);
DISPLAY 0.489362 (-2873 2558);
PAINT MONO (-2873 2558);
FORCEPROP 2 LAST BOM_COST IO_SLOT
J 0
(-3375 2650);
DISPLAY 0.829787 (-3375 2650);
DISPLAY INVISIBLE (-3375 2650);
FORCEPROP 2 LAST CDS_LIB standard
J 0
(-2875 2550);
DISPLAY INVISIBLE (-2875 2550);
FORCEPROP 1 LAST BODY_TYPE PLUMBING
J 2
(-2875 2500);
DISPLAY 0.702128 (-2875 2500);
PAINT GREEN (-2875 2500);
DISPLAY INVISIBLE (-2875 2500);
FORCEPROP 1 LAST HDL_TAP TRUE
J 2
(-3200 2425);
DISPLAY 0.702128 (-3200 2425);
PAINT GREEN (-3200 2425);
DISPLAY INVISIBLE (-3200 2425);
FORCEPROP 1 LAST PATH I190
J 2
(-2873 2550);
DISPLAY 0.872340 (-2873 2550);
PAINT GREEN (-2873 2550);
DISPLAY INVISIBLE (-2873 2550);
FORCEPROP 2 LAST ROOM RISER1
J 0
(-3375 2600);
DISPLAY 0.829787 (-3375 2600);
PAINT RED (-3375 2600);
DISPLAY INVISIBLE (-3375 2600);
FORCEADD TAP..6
R 2
(-2875 2350);
FORCEPROP 3 LASTPIN (-2925 2350) SIG_NAME P5E_CPU1_P1_TX_DN<5>
J 0
(-2915 2360);
DISPLAY 0.659574 (-2915 2360);
PAINT MONO (-2915 2360);
DISPLAY INVISIBLE (-2915 2360);
FORCEPROP 1 LASTPIN (-2925 2350) BN 5
J 2
(-2873 2358);
DISPLAY 0.489362 (-2873 2358);
PAINT MONO (-2873 2358);
FORCEPROP 2 LAST BOM_COST IO_SLOT
J 0
(-3375 2450);
DISPLAY 0.829787 (-3375 2450);
DISPLAY INVISIBLE (-3375 2450);
FORCEPROP 2 LAST CDS_LIB standard
J 0
(-2875 2350);
DISPLAY INVISIBLE (-2875 2350);
FORCEPROP 1 LAST BODY_TYPE PLUMBING
J 2
(-2875 2300);
DISPLAY 0.702128 (-2875 2300);
PAINT GREEN (-2875 2300);
DISPLAY INVISIBLE (-2875 2300);
FORCEPROP 1 LAST HDL_TAP TRUE
J 2
(-3200 2225);
DISPLAY 0.702128 (-3200 2225);
PAINT GREEN (-3200 2225);
DISPLAY INVISIBLE (-3200 2225);
FORCEPROP 1 LAST PATH I191
J 2
(-2873 2350);
DISPLAY 0.872340 (-2873 2350);
PAINT GREEN (-2873 2350);
DISPLAY INVISIBLE (-2873 2350);
FORCEPROP 2 LAST ROOM RISER1
J 0
(-3375 2400);
DISPLAY 0.829787 (-3375 2400);
PAINT RED (-3375 2400);
DISPLAY INVISIBLE (-3375 2400);
FORCEADD TAP..6
R 2
(-2875 2250);
FORCEPROP 3 LASTPIN (-2925 2250) SIG_NAME P5E_CPU1_P1_TX_DN<6>
J 0
(-2915 2260);
DISPLAY 0.659574 (-2915 2260);
PAINT MONO (-2915 2260);
DISPLAY INVISIBLE (-2915 2260);
FORCEPROP 1 LASTPIN (-2925 2250) BN 6
J 2
(-2873 2258);
DISPLAY 0.489362 (-2873 2258);
PAINT MONO (-2873 2258);
FORCEPROP 2 LAST BOM_COST IO_SLOT
J 0
(-3375 2350);
DISPLAY 0.829787 (-3375 2350);
DISPLAY INVISIBLE (-3375 2350);
FORCEPROP 2 LAST CDS_LIB standard
J 0
(-2875 2250);
DISPLAY INVISIBLE (-2875 2250);
FORCEPROP 1 LAST BODY_TYPE PLUMBING
J 2
(-2875 2200);
DISPLAY 0.702128 (-2875 2200);
PAINT GREEN (-2875 2200);
DISPLAY INVISIBLE (-2875 2200);
FORCEPROP 1 LAST HDL_TAP TRUE
J 2
(-3200 2125);
DISPLAY 0.702128 (-3200 2125);
PAINT GREEN (-3200 2125);
DISPLAY INVISIBLE (-3200 2125);
FORCEPROP 1 LAST PATH I192
J 2
(-2873 2250);
DISPLAY 0.872340 (-2873 2250);
PAINT GREEN (-2873 2250);
DISPLAY INVISIBLE (-2873 2250);
FORCEPROP 2 LAST ROOM RISER1
J 0
(-3375 2300);
DISPLAY 0.829787 (-3375 2300);
PAINT RED (-3375 2300);
DISPLAY INVISIBLE (-3375 2300);
FORCEADD TAP..6
R 2
(-2875 2050);
FORCEPROP 3 LASTPIN (-2925 2050) SIG_NAME P5E_CPU1_P1_TX_DN<8>
J 0
(-2915 2060);
DISPLAY 0.659574 (-2915 2060);
PAINT MONO (-2915 2060);
DISPLAY INVISIBLE (-2915 2060);
FORCEPROP 1 LASTPIN (-2925 2050) BN 8
J 2
(-2873 2058);
DISPLAY 0.489362 (-2873 2058);
PAINT MONO (-2873 2058);
FORCEPROP 2 LAST BOM_COST IO_SLOT
J 0
(-3375 2150);
DISPLAY 0.829787 (-3375 2150);
DISPLAY INVISIBLE (-3375 2150);
FORCEPROP 2 LAST CDS_LIB standard
J 0
(-2875 2050);
DISPLAY INVISIBLE (-2875 2050);
FORCEPROP 1 LAST BODY_TYPE PLUMBING
J 2
(-2875 2000);
DISPLAY 0.702128 (-2875 2000);
PAINT GREEN (-2875 2000);
DISPLAY INVISIBLE (-2875 2000);
FORCEPROP 1 LAST HDL_TAP TRUE
J 2
(-3200 1925);
DISPLAY 0.702128 (-3200 1925);
PAINT GREEN (-3200 1925);
DISPLAY INVISIBLE (-3200 1925);
FORCEPROP 1 LAST PATH I193
J 2
(-2873 2050);
DISPLAY 0.872340 (-2873 2050);
PAINT GREEN (-2873 2050);
DISPLAY INVISIBLE (-2873 2050);
FORCEPROP 2 LAST ROOM RISER1
J 0
(-3375 2100);
DISPLAY 0.829787 (-3375 2100);
PAINT RED (-3375 2100);
DISPLAY INVISIBLE (-3375 2100);
FORCEADD TAP..6
R 2
(-2875 2150);
FORCEPROP 3 LASTPIN (-2925 2150) SIG_NAME P5E_CPU1_P1_TX_DN<7>
J 0
(-2915 2160);
DISPLAY 0.659574 (-2915 2160);
PAINT MONO (-2915 2160);
DISPLAY INVISIBLE (-2915 2160);
FORCEPROP 1 LASTPIN (-2925 2150) BN 7
J 2
(-2873 2158);
DISPLAY 0.489362 (-2873 2158);
PAINT MONO (-2873 2158);
FORCEPROP 2 LAST BOM_COST IO_SLOT
J 0
(-3375 2250);
DISPLAY 0.829787 (-3375 2250);
DISPLAY INVISIBLE (-3375 2250);
FORCEPROP 2 LAST CDS_LIB standard
J 0
(-2875 2150);
DISPLAY INVISIBLE (-2875 2150);
FORCEPROP 1 LAST BODY_TYPE PLUMBING
J 2
(-2875 2100);
DISPLAY 0.702128 (-2875 2100);
PAINT GREEN (-2875 2100);
DISPLAY INVISIBLE (-2875 2100);
FORCEPROP 1 LAST HDL_TAP TRUE
J 2
(-3200 2025);
DISPLAY 0.702128 (-3200 2025);
PAINT GREEN (-3200 2025);
DISPLAY INVISIBLE (-3200 2025);
FORCEPROP 1 LAST PATH I194
J 2
(-2873 2150);
DISPLAY 0.872340 (-2873 2150);
PAINT GREEN (-2873 2150);
DISPLAY INVISIBLE (-2873 2150);
FORCEPROP 2 LAST ROOM RISER1
J 0
(-3375 2200);
DISPLAY 0.829787 (-3375 2200);
PAINT RED (-3375 2200);
DISPLAY INVISIBLE (-3375 2200);
FORCEADD TAP..6
R 2
(-3025 2900);
FORCEPROP 3 LASTPIN (-3075 2900) SIG_NAME P5E_CPU1_P1_TX_DP<0>
J 0
(-3065 2910);
DISPLAY 0.659574 (-3065 2910);
PAINT MONO (-3065 2910);
DISPLAY INVISIBLE (-3065 2910);
FORCEPROP 1 LASTPIN (-3075 2900) BN 0
J 2
(-3023 2908);
DISPLAY 0.489362 (-3023 2908);
PAINT MONO (-3023 2908);
FORCEPROP 2 LAST BOM_COST IO_SLOT
J 0
(-3525 3000);
DISPLAY 0.829787 (-3525 3000);
DISPLAY INVISIBLE (-3525 3000);
FORCEPROP 2 LAST CDS_LIB mstr_standard
J 0
(-3025 2900);
DISPLAY INVISIBLE (-3025 2900);
FORCEPROP 1 LAST BODY_TYPE PLUMBING
J 2
(-3025 2850);
DISPLAY 0.702128 (-3025 2850);
PAINT GREEN (-3025 2850);
DISPLAY INVISIBLE (-3025 2850);
FORCEPROP 1 LAST HDL_TAP TRUE
J 2
(-3350 2775);
DISPLAY 0.702128 (-3350 2775);
PAINT GREEN (-3350 2775);
DISPLAY INVISIBLE (-3350 2775);
FORCEPROP 1 LAST PATH I196
J 2
(-3023 2900);
DISPLAY 0.872340 (-3023 2900);
PAINT GREEN (-3023 2900);
DISPLAY INVISIBLE (-3023 2900);
FORCEPROP 2 LAST ROOM RISER1
J 0
(-3525 2950);
DISPLAY 0.829787 (-3525 2950);
PAINT RED (-3525 2950);
DISPLAY INVISIBLE (-3525 2950);
FORCEADD TAP..6
R 2
(-3025 2700);
FORCEPROP 3 LASTPIN (-3075 2700) SIG_NAME P5E_CPU1_P1_TX_DP<2>
J 0
(-3065 2710);
DISPLAY 0.659574 (-3065 2710);
PAINT MONO (-3065 2710);
DISPLAY INVISIBLE (-3065 2710);
FORCEPROP 1 LASTPIN (-3075 2700) BN 2
J 2
(-3023 2708);
DISPLAY 0.489362 (-3023 2708);
PAINT MONO (-3023 2708);
FORCEPROP 2 LAST BOM_COST IO_SLOT
J 0
(-3525 2800);
DISPLAY 0.829787 (-3525 2800);
DISPLAY INVISIBLE (-3525 2800);
FORCEPROP 2 LAST CDS_LIB standard
J 0
(-3025 2700);
DISPLAY INVISIBLE (-3025 2700);
FORCEPROP 1 LAST BODY_TYPE PLUMBING
J 2
(-3025 2650);
DISPLAY 0.702128 (-3025 2650);
PAINT GREEN (-3025 2650);
DISPLAY INVISIBLE (-3025 2650);
FORCEPROP 1 LAST HDL_TAP TRUE
J 2
(-3350 2575);
DISPLAY 0.702128 (-3350 2575);
PAINT GREEN (-3350 2575);
DISPLAY INVISIBLE (-3350 2575);
FORCEPROP 1 LAST PATH I197
J 2
(-3023 2700);
DISPLAY 0.872340 (-3023 2700);
PAINT GREEN (-3023 2700);
DISPLAY INVISIBLE (-3023 2700);
FORCEPROP 2 LAST ROOM RISER1
J 0
(-3525 2750);
DISPLAY 0.829787 (-3525 2750);
PAINT RED (-3525 2750);
DISPLAY INVISIBLE (-3525 2750);
FORCEADD TAP..6
R 2
(-3025 2800);
FORCEPROP 3 LASTPIN (-3075 2800) SIG_NAME P5E_CPU1_P1_TX_DP<1>
J 0
(-3065 2810);
DISPLAY 0.659574 (-3065 2810);
PAINT MONO (-3065 2810);
DISPLAY INVISIBLE (-3065 2810);
FORCEPROP 1 LASTPIN (-3075 2800) BN 1
J 2
(-3023 2808);
DISPLAY 0.489362 (-3023 2808);
PAINT MONO (-3023 2808);
FORCEPROP 2 LAST BOM_COST IO_SLOT
J 0
(-3525 2900);
DISPLAY 0.829787 (-3525 2900);
DISPLAY INVISIBLE (-3525 2900);
FORCEPROP 2 LAST CDS_LIB mstr_standard
J 0
(-3025 2800);
DISPLAY INVISIBLE (-3025 2800);
FORCEPROP 1 LAST BODY_TYPE PLUMBING
J 2
(-3025 2750);
DISPLAY 0.702128 (-3025 2750);
PAINT GREEN (-3025 2750);
DISPLAY INVISIBLE (-3025 2750);
FORCEPROP 1 LAST HDL_TAP TRUE
J 2
(-3350 2675);
DISPLAY 0.702128 (-3350 2675);
PAINT GREEN (-3350 2675);
DISPLAY INVISIBLE (-3350 2675);
FORCEPROP 1 LAST PATH I198
J 2
(-3023 2800);
DISPLAY 0.872340 (-3023 2800);
PAINT GREEN (-3023 2800);
DISPLAY INVISIBLE (-3023 2800);
FORCEPROP 2 LAST ROOM RISER1
J 0
(-3525 2850);
DISPLAY 0.829787 (-3525 2850);
PAINT RED (-3525 2850);
DISPLAY INVISIBLE (-3525 2850);
FORCEADD TAP..6
R 2
(-3025 2600);
FORCEPROP 3 LASTPIN (-3075 2600) SIG_NAME P5E_CPU1_P1_TX_DP<3>
J 0
(-3065 2610);
DISPLAY 0.659574 (-3065 2610);
PAINT MONO (-3065 2610);
DISPLAY INVISIBLE (-3065 2610);
FORCEPROP 1 LASTPIN (-3075 2600) BN 3
J 2
(-3023 2608);
DISPLAY 0.489362 (-3023 2608);
PAINT MONO (-3023 2608);
FORCEPROP 2 LAST BOM_COST IO_SLOT
J 0
(-3525 2700);
DISPLAY 0.829787 (-3525 2700);
DISPLAY INVISIBLE (-3525 2700);
FORCEPROP 2 LAST CDS_LIB standard
J 0
(-3025 2600);
DISPLAY INVISIBLE (-3025 2600);
FORCEPROP 1 LAST BODY_TYPE PLUMBING
J 2
(-3025 2550);
DISPLAY 0.702128 (-3025 2550);
PAINT GREEN (-3025 2550);
DISPLAY INVISIBLE (-3025 2550);
FORCEPROP 1 LAST HDL_TAP TRUE
J 2
(-3350 2475);
DISPLAY 0.702128 (-3350 2475);
PAINT GREEN (-3350 2475);
DISPLAY INVISIBLE (-3350 2475);
FORCEPROP 1 LAST PATH I199
J 2
(-3023 2600);
DISPLAY 0.872340 (-3023 2600);
PAINT GREEN (-3023 2600);
DISPLAY INVISIBLE (-3023 2600);
FORCEPROP 2 LAST ROOM RISER1
J 0
(-3525 2650);
DISPLAY 0.829787 (-3525 2650);
PAINT RED (-3525 2650);
DISPLAY INVISIBLE (-3525 2650);
FORCEADD TAP..6
R 2
(-3025 2500);
FORCEPROP 3 LASTPIN (-3075 2500) SIG_NAME P5E_CPU1_P1_TX_DP<4>
J 0
(-3065 2510);
DISPLAY 0.659574 (-3065 2510);
PAINT MONO (-3065 2510);
DISPLAY INVISIBLE (-3065 2510);
FORCEPROP 1 LASTPIN (-3075 2500) BN 4
J 2
(-3023 2508);
DISPLAY 0.489362 (-3023 2508);
PAINT MONO (-3023 2508);
FORCEPROP 2 LAST BOM_COST IO_SLOT
J 0
(-3525 2600);
DISPLAY 0.829787 (-3525 2600);
DISPLAY INVISIBLE (-3525 2600);
FORCEPROP 2 LAST CDS_LIB standard
J 0
(-3025 2500);
DISPLAY INVISIBLE (-3025 2500);
FORCEPROP 1 LAST BODY_TYPE PLUMBING
J 2
(-3025 2450);
DISPLAY 0.702128 (-3025 2450);
PAINT GREEN (-3025 2450);
DISPLAY INVISIBLE (-3025 2450);
FORCEPROP 1 LAST HDL_TAP TRUE
J 2
(-3350 2375);
DISPLAY 0.702128 (-3350 2375);
PAINT GREEN (-3350 2375);
DISPLAY INVISIBLE (-3350 2375);
FORCEPROP 1 LAST PATH I200
J 2
(-3023 2500);
DISPLAY 0.872340 (-3023 2500);
PAINT GREEN (-3023 2500);
DISPLAY INVISIBLE (-3023 2500);
FORCEPROP 2 LAST ROOM RISER1
J 0
(-3525 2550);
DISPLAY 0.829787 (-3525 2550);
PAINT RED (-3525 2550);
DISPLAY INVISIBLE (-3525 2550);
FORCEADD TAP..6
R 2
(-3025 2400);
FORCEPROP 3 LASTPIN (-3075 2400) SIG_NAME P5E_CPU1_P1_TX_DP<5>
J 0
(-3065 2410);
DISPLAY 0.659574 (-3065 2410);
PAINT MONO (-3065 2410);
DISPLAY INVISIBLE (-3065 2410);
FORCEPROP 1 LASTPIN (-3075 2400) BN 5
J 2
(-3023 2408);
DISPLAY 0.489362 (-3023 2408);
PAINT MONO (-3023 2408);
FORCEPROP 2 LAST BOM_COST IO_SLOT
J 0
(-3525 2500);
DISPLAY 0.829787 (-3525 2500);
DISPLAY INVISIBLE (-3525 2500);
FORCEPROP 2 LAST CDS_LIB standard
J 0
(-3025 2400);
DISPLAY INVISIBLE (-3025 2400);
FORCEPROP 1 LAST BODY_TYPE PLUMBING
J 2
(-3025 2350);
DISPLAY 0.702128 (-3025 2350);
PAINT GREEN (-3025 2350);
DISPLAY INVISIBLE (-3025 2350);
FORCEPROP 1 LAST HDL_TAP TRUE
J 2
(-3350 2275);
DISPLAY 0.702128 (-3350 2275);
PAINT GREEN (-3350 2275);
DISPLAY INVISIBLE (-3350 2275);
FORCEPROP 1 LAST PATH I201
J 2
(-3023 2400);
DISPLAY 0.872340 (-3023 2400);
PAINT GREEN (-3023 2400);
DISPLAY INVISIBLE (-3023 2400);
FORCEPROP 2 LAST ROOM RISER1
J 0
(-3525 2450);
DISPLAY 0.829787 (-3525 2450);
PAINT RED (-3525 2450);
DISPLAY INVISIBLE (-3525 2450);
FORCEADD TAP..6
R 2
(-3025 2300);
FORCEPROP 3 LASTPIN (-3075 2300) SIG_NAME P5E_CPU1_P1_TX_DP<6>
J 0
(-3065 2310);
DISPLAY 0.659574 (-3065 2310);
PAINT MONO (-3065 2310);
DISPLAY INVISIBLE (-3065 2310);
FORCEPROP 1 LASTPIN (-3075 2300) BN 6
J 2
(-3023 2308);
DISPLAY 0.489362 (-3023 2308);
PAINT MONO (-3023 2308);
FORCEPROP 2 LAST BOM_COST IO_SLOT
J 0
(-3525 2400);
DISPLAY 0.829787 (-3525 2400);
DISPLAY INVISIBLE (-3525 2400);
FORCEPROP 2 LAST CDS_LIB standard
J 0
(-3025 2300);
DISPLAY INVISIBLE (-3025 2300);
FORCEPROP 1 LAST BODY_TYPE PLUMBING
J 2
(-3025 2250);
DISPLAY 0.702128 (-3025 2250);
PAINT GREEN (-3025 2250);
DISPLAY INVISIBLE (-3025 2250);
FORCEPROP 1 LAST HDL_TAP TRUE
J 2
(-3350 2175);
DISPLAY 0.702128 (-3350 2175);
PAINT GREEN (-3350 2175);
DISPLAY INVISIBLE (-3350 2175);
FORCEPROP 1 LAST PATH I202
J 2
(-3023 2300);
DISPLAY 0.872340 (-3023 2300);
PAINT GREEN (-3023 2300);
DISPLAY INVISIBLE (-3023 2300);
FORCEPROP 2 LAST ROOM RISER1
J 0
(-3525 2350);
DISPLAY 0.829787 (-3525 2350);
PAINT RED (-3525 2350);
DISPLAY INVISIBLE (-3525 2350);
FORCEADD TAP..6
R 2
(-3025 2200);
FORCEPROP 3 LASTPIN (-3075 2200) SIG_NAME P5E_CPU1_P1_TX_DP<7>
J 0
(-3065 2210);
DISPLAY 0.659574 (-3065 2210);
PAINT MONO (-3065 2210);
DISPLAY INVISIBLE (-3065 2210);
FORCEPROP 1 LASTPIN (-3075 2200) BN 7
J 2
(-3023 2208);
DISPLAY 0.489362 (-3023 2208);
PAINT MONO (-3023 2208);
FORCEPROP 2 LAST BOM_COST IO_SLOT
J 0
(-3525 2300);
DISPLAY 0.829787 (-3525 2300);
DISPLAY INVISIBLE (-3525 2300);
FORCEPROP 2 LAST CDS_LIB standard
J 0
(-3025 2200);
DISPLAY INVISIBLE (-3025 2200);
FORCEPROP 1 LAST BODY_TYPE PLUMBING
J 2
(-3025 2150);
DISPLAY 0.702128 (-3025 2150);
PAINT GREEN (-3025 2150);
DISPLAY INVISIBLE (-3025 2150);
FORCEPROP 1 LAST HDL_TAP TRUE
J 2
(-3350 2075);
DISPLAY 0.702128 (-3350 2075);
PAINT GREEN (-3350 2075);
DISPLAY INVISIBLE (-3350 2075);
FORCEPROP 1 LAST PATH I203
J 2
(-3023 2200);
DISPLAY 0.872340 (-3023 2200);
PAINT GREEN (-3023 2200);
DISPLAY INVISIBLE (-3023 2200);
FORCEPROP 2 LAST ROOM RISER1
J 0
(-3525 2250);
DISPLAY 0.829787 (-3525 2250);
PAINT RED (-3525 2250);
DISPLAY INVISIBLE (-3525 2250);
FORCEADD TAP..6
R 2
(-3025 2100);
FORCEPROP 3 LASTPIN (-3075 2100) SIG_NAME P5E_CPU1_P1_TX_DP<8>
J 0
(-3065 2110);
DISPLAY 0.659574 (-3065 2110);
PAINT MONO (-3065 2110);
DISPLAY INVISIBLE (-3065 2110);
FORCEPROP 1 LASTPIN (-3075 2100) BN 8
J 2
(-3023 2108);
DISPLAY 0.489362 (-3023 2108);
PAINT MONO (-3023 2108);
FORCEPROP 2 LAST BOM_COST IO_SLOT
J 0
(-3525 2200);
DISPLAY 0.829787 (-3525 2200);
DISPLAY INVISIBLE (-3525 2200);
FORCEPROP 2 LAST CDS_LIB standard
J 0
(-3025 2100);
DISPLAY INVISIBLE (-3025 2100);
FORCEPROP 1 LAST BODY_TYPE PLUMBING
J 2
(-3025 2050);
DISPLAY 0.702128 (-3025 2050);
PAINT GREEN (-3025 2050);
DISPLAY INVISIBLE (-3025 2050);
FORCEPROP 1 LAST HDL_TAP TRUE
J 2
(-3350 1975);
DISPLAY 0.702128 (-3350 1975);
PAINT GREEN (-3350 1975);
DISPLAY INVISIBLE (-3350 1975);
FORCEPROP 1 LAST PATH I204
J 2
(-3023 2100);
DISPLAY 0.872340 (-3023 2100);
PAINT GREEN (-3023 2100);
DISPLAY INVISIBLE (-3023 2100);
FORCEPROP 2 LAST ROOM RISER1
J 0
(-3525 2150);
DISPLAY 0.829787 (-3525 2150);
PAINT RED (-3525 2150);
DISPLAY INVISIBLE (-3525 2150);
FORCEADD TAP..6
R 2
(-2875 1950);
FORCEPROP 3 LASTPIN (-2925 1950) SIG_NAME P5E_CPU1_P1_TX_DN<9>
J 0
(-2915 1960);
DISPLAY 0.659574 (-2915 1960);
PAINT MONO (-2915 1960);
DISPLAY INVISIBLE (-2915 1960);
FORCEPROP 1 LASTPIN (-2925 1950) BN 9
J 2
(-2873 1958);
DISPLAY 0.489362 (-2873 1958);
PAINT MONO (-2873 1958);
FORCEPROP 2 LAST BOM_COST IO_SLOT
J 0
(-3375 2050);
DISPLAY 0.829787 (-3375 2050);
DISPLAY INVISIBLE (-3375 2050);
FORCEPROP 2 LAST CDS_LIB standard
J 0
(-2875 1950);
DISPLAY INVISIBLE (-2875 1950);
FORCEPROP 1 LAST BODY_TYPE PLUMBING
J 2
(-2875 1900);
DISPLAY 0.702128 (-2875 1900);
PAINT GREEN (-2875 1900);
DISPLAY INVISIBLE (-2875 1900);
FORCEPROP 1 LAST HDL_TAP TRUE
J 2
(-3200 1825);
DISPLAY 0.702128 (-3200 1825);
PAINT GREEN (-3200 1825);
DISPLAY INVISIBLE (-3200 1825);
FORCEPROP 1 LAST PATH I205
J 2
(-2873 1950);
DISPLAY 0.872340 (-2873 1950);
PAINT GREEN (-2873 1950);
DISPLAY INVISIBLE (-2873 1950);
FORCEPROP 2 LAST ROOM RISER1
J 0
(-3375 2000);
DISPLAY 0.829787 (-3375 2000);
PAINT RED (-3375 2000);
DISPLAY INVISIBLE (-3375 2000);
FORCEADD TAP..6
R 2
(-2875 1850);
FORCEPROP 3 LASTPIN (-2925 1850) SIG_NAME P5E_CPU1_P1_TX_DN<10>
J 0
(-2915 1860);
DISPLAY 0.659574 (-2915 1860);
PAINT MONO (-2915 1860);
DISPLAY INVISIBLE (-2915 1860);
FORCEPROP 1 LASTPIN (-2925 1850) BN 10
J 2
(-2873 1858);
DISPLAY 0.489362 (-2873 1858);
PAINT MONO (-2873 1858);
FORCEPROP 2 LAST BOM_COST IO_SLOT
J 0
(-3375 1950);
DISPLAY 0.829787 (-3375 1950);
DISPLAY INVISIBLE (-3375 1950);
FORCEPROP 2 LAST CDS_LIB standard
J 0
(-2875 1850);
DISPLAY INVISIBLE (-2875 1850);
FORCEPROP 1 LAST BODY_TYPE PLUMBING
J 2
(-2875 1800);
DISPLAY 0.702128 (-2875 1800);
PAINT GREEN (-2875 1800);
DISPLAY INVISIBLE (-2875 1800);
FORCEPROP 1 LAST HDL_TAP TRUE
J 2
(-3200 1725);
DISPLAY 0.702128 (-3200 1725);
PAINT GREEN (-3200 1725);
DISPLAY INVISIBLE (-3200 1725);
FORCEPROP 1 LAST PATH I206
J 2
(-2873 1850);
DISPLAY 0.872340 (-2873 1850);
PAINT GREEN (-2873 1850);
DISPLAY INVISIBLE (-2873 1850);
FORCEPROP 2 LAST ROOM RISER1
J 0
(-3375 1900);
DISPLAY 0.829787 (-3375 1900);
PAINT RED (-3375 1900);
DISPLAY INVISIBLE (-3375 1900);
FORCEADD TAP..6
R 2
(-2875 1750);
FORCEPROP 3 LASTPIN (-2925 1750) SIG_NAME P5E_CPU1_P1_TX_DN<11>
J 0
(-2915 1760);
DISPLAY 0.659574 (-2915 1760);
PAINT MONO (-2915 1760);
DISPLAY INVISIBLE (-2915 1760);
FORCEPROP 1 LASTPIN (-2925 1750) BN 11
J 2
(-2873 1758);
DISPLAY 0.489362 (-2873 1758);
PAINT MONO (-2873 1758);
FORCEPROP 2 LAST BOM_COST IO_SLOT
J 0
(-3375 1850);
DISPLAY 0.829787 (-3375 1850);
DISPLAY INVISIBLE (-3375 1850);
FORCEPROP 2 LAST CDS_LIB standard
J 0
(-2875 1750);
DISPLAY INVISIBLE (-2875 1750);
FORCEPROP 1 LAST BODY_TYPE PLUMBING
J 2
(-2875 1700);
DISPLAY 0.702128 (-2875 1700);
PAINT GREEN (-2875 1700);
DISPLAY INVISIBLE (-2875 1700);
FORCEPROP 1 LAST HDL_TAP TRUE
J 2
(-3200 1625);
DISPLAY 0.702128 (-3200 1625);
PAINT GREEN (-3200 1625);
DISPLAY INVISIBLE (-3200 1625);
FORCEPROP 1 LAST PATH I207
J 2
(-2873 1750);
DISPLAY 0.872340 (-2873 1750);
PAINT GREEN (-2873 1750);
DISPLAY INVISIBLE (-2873 1750);
FORCEPROP 2 LAST ROOM RISER1
J 0
(-3375 1800);
DISPLAY 0.829787 (-3375 1800);
PAINT RED (-3375 1800);
DISPLAY INVISIBLE (-3375 1800);
FORCEADD TAP..6
R 2
(-2875 1550);
FORCEPROP 3 LASTPIN (-2925 1550) SIG_NAME P5E_CPU1_P1_TX_DN<13>
J 0
(-2915 1560);
DISPLAY 0.659574 (-2915 1560);
PAINT MONO (-2915 1560);
DISPLAY INVISIBLE (-2915 1560);
FORCEPROP 1 LASTPIN (-2925 1550) BN 13
J 2
(-2873 1558);
DISPLAY 0.489362 (-2873 1558);
PAINT MONO (-2873 1558);
FORCEPROP 2 LAST BOM_COST IO_SLOT
J 0
(-3375 1650);
DISPLAY 0.829787 (-3375 1650);
DISPLAY INVISIBLE (-3375 1650);
FORCEPROP 2 LAST CDS_LIB standard
J 0
(-2875 1550);
DISPLAY INVISIBLE (-2875 1550);
FORCEPROP 1 LAST BODY_TYPE PLUMBING
J 2
(-2875 1500);
DISPLAY 0.702128 (-2875 1500);
PAINT GREEN (-2875 1500);
DISPLAY INVISIBLE (-2875 1500);
FORCEPROP 1 LAST HDL_TAP TRUE
J 2
(-3200 1425);
DISPLAY 0.702128 (-3200 1425);
PAINT GREEN (-3200 1425);
DISPLAY INVISIBLE (-3200 1425);
FORCEPROP 1 LAST PATH I208
J 2
(-2873 1550);
DISPLAY 0.872340 (-2873 1550);
PAINT GREEN (-2873 1550);
DISPLAY INVISIBLE (-2873 1550);
FORCEPROP 2 LAST ROOM RISER1
J 0
(-3375 1600);
DISPLAY 0.829787 (-3375 1600);
PAINT RED (-3375 1600);
DISPLAY INVISIBLE (-3375 1600);
FORCEADD TAP..6
R 2
(-2875 1650);
FORCEPROP 3 LASTPIN (-2925 1650) SIG_NAME P5E_CPU1_P1_TX_DN<12>
J 0
(-2915 1660);
DISPLAY 0.659574 (-2915 1660);
PAINT MONO (-2915 1660);
DISPLAY INVISIBLE (-2915 1660);
FORCEPROP 1 LASTPIN (-2925 1650) BN 12
J 2
(-2873 1658);
DISPLAY 0.489362 (-2873 1658);
PAINT MONO (-2873 1658);
FORCEPROP 2 LAST BOM_COST IO_SLOT
J 0
(-3375 1750);
DISPLAY 0.829787 (-3375 1750);
DISPLAY INVISIBLE (-3375 1750);
FORCEPROP 2 LAST CDS_LIB standard
J 0
(-2875 1650);
DISPLAY INVISIBLE (-2875 1650);
FORCEPROP 1 LAST BODY_TYPE PLUMBING
J 2
(-2875 1600);
DISPLAY 0.702128 (-2875 1600);
PAINT GREEN (-2875 1600);
DISPLAY INVISIBLE (-2875 1600);
FORCEPROP 1 LAST HDL_TAP TRUE
J 2
(-3200 1525);
DISPLAY 0.702128 (-3200 1525);
PAINT GREEN (-3200 1525);
DISPLAY INVISIBLE (-3200 1525);
FORCEPROP 1 LAST PATH I209
J 2
(-2873 1650);
DISPLAY 0.872340 (-2873 1650);
PAINT GREEN (-2873 1650);
DISPLAY INVISIBLE (-2873 1650);
FORCEPROP 2 LAST ROOM RISER1
J 0
(-3375 1700);
DISPLAY 0.829787 (-3375 1700);
PAINT RED (-3375 1700);
DISPLAY INVISIBLE (-3375 1700);
FORCEADD TAP..6
R 2
(-2875 1450);
FORCEPROP 3 LASTPIN (-2925 1450) SIG_NAME P5E_CPU1_P1_TX_DN<14>
J 0
(-2915 1460);
DISPLAY 0.659574 (-2915 1460);
PAINT MONO (-2915 1460);
DISPLAY INVISIBLE (-2915 1460);
FORCEPROP 1 LASTPIN (-2925 1450) BN 14
J 2
(-2873 1458);
DISPLAY 0.489362 (-2873 1458);
PAINT MONO (-2873 1458);
FORCEPROP 2 LAST CDS_LIB standard
J 0
(-2875 1450);
DISPLAY INVISIBLE (-2875 1450);
FORCEPROP 2 LAST BOM_COST IO_SLOT
J 0
(-3375 1550);
DISPLAY 0.829787 (-3375 1550);
DISPLAY INVISIBLE (-3375 1550);
FORCEPROP 1 LAST BODY_TYPE PLUMBING
J 2
(-2875 1400);
DISPLAY 0.702128 (-2875 1400);
PAINT GREEN (-2875 1400);
DISPLAY INVISIBLE (-2875 1400);
FORCEPROP 1 LAST HDL_TAP TRUE
J 2
(-3200 1325);
DISPLAY 0.702128 (-3200 1325);
PAINT GREEN (-3200 1325);
DISPLAY INVISIBLE (-3200 1325);
FORCEPROP 1 LAST PATH I210
J 2
(-2873 1450);
DISPLAY 0.872340 (-2873 1450);
PAINT GREEN (-2873 1450);
DISPLAY INVISIBLE (-2873 1450);
FORCEPROP 2 LAST ROOM RISER1
J 0
(-3375 1500);
DISPLAY 0.829787 (-3375 1500);
PAINT RED (-3375 1500);
DISPLAY INVISIBLE (-3375 1500);
FORCEADD TAP..6
R 2
(-2875 1350);
FORCEPROP 3 LASTPIN (-2925 1350) SIG_NAME P5E_CPU1_P1_TX_DN<15>
J 0
(-2915 1360);
DISPLAY 0.659574 (-2915 1360);
PAINT MONO (-2915 1360);
DISPLAY INVISIBLE (-2915 1360);
FORCEPROP 1 LASTPIN (-2925 1350) BN 15
J 2
(-2873 1358);
DISPLAY 0.489362 (-2873 1358);
PAINT MONO (-2873 1358);
FORCEPROP 2 LAST BOM_COST IO_SLOT
J 0
(-3375 1450);
DISPLAY 0.829787 (-3375 1450);
DISPLAY INVISIBLE (-3375 1450);
FORCEPROP 2 LAST CDS_LIB standard
J 0
(-2875 1350);
DISPLAY INVISIBLE (-2875 1350);
FORCEPROP 1 LAST BODY_TYPE PLUMBING
J 2
(-2875 1300);
DISPLAY 0.702128 (-2875 1300);
PAINT GREEN (-2875 1300);
DISPLAY INVISIBLE (-2875 1300);
FORCEPROP 1 LAST HDL_TAP TRUE
J 2
(-3200 1225);
DISPLAY 0.702128 (-3200 1225);
PAINT GREEN (-3200 1225);
DISPLAY INVISIBLE (-3200 1225);
FORCEPROP 1 LAST PATH I211
J 2
(-2873 1350);
DISPLAY 0.872340 (-2873 1350);
PAINT GREEN (-2873 1350);
DISPLAY INVISIBLE (-2873 1350);
FORCEPROP 2 LAST ROOM RISER1
J 0
(-3375 1400);
DISPLAY 0.829787 (-3375 1400);
PAINT RED (-3375 1400);
DISPLAY INVISIBLE (-3375 1400);
FORCEADD TAP..6
R 2
(-3025 2000);
FORCEPROP 3 LASTPIN (-3075 2000) SIG_NAME P5E_CPU1_P1_TX_DP<9>
J 0
(-3065 2010);
DISPLAY 0.659574 (-3065 2010);
PAINT MONO (-3065 2010);
DISPLAY INVISIBLE (-3065 2010);
FORCEPROP 1 LASTPIN (-3075 2000) BN 9
J 2
(-3023 2008);
DISPLAY 0.489362 (-3023 2008);
PAINT MONO (-3023 2008);
FORCEPROP 2 LAST BOM_COST IO_SLOT
J 0
(-3525 2100);
DISPLAY 0.829787 (-3525 2100);
DISPLAY INVISIBLE (-3525 2100);
FORCEPROP 2 LAST CDS_LIB standard
J 0
(-3025 2000);
DISPLAY INVISIBLE (-3025 2000);
FORCEPROP 1 LAST BODY_TYPE PLUMBING
J 2
(-3025 1950);
DISPLAY 0.702128 (-3025 1950);
PAINT GREEN (-3025 1950);
DISPLAY INVISIBLE (-3025 1950);
FORCEPROP 1 LAST HDL_TAP TRUE
J 2
(-3350 1875);
DISPLAY 0.702128 (-3350 1875);
PAINT GREEN (-3350 1875);
DISPLAY INVISIBLE (-3350 1875);
FORCEPROP 1 LAST PATH I212
J 2
(-3023 2000);
DISPLAY 0.872340 (-3023 2000);
PAINT GREEN (-3023 2000);
DISPLAY INVISIBLE (-3023 2000);
FORCEPROP 2 LAST ROOM RISER1
J 0
(-3525 2050);
DISPLAY 0.829787 (-3525 2050);
PAINT RED (-3525 2050);
DISPLAY INVISIBLE (-3525 2050);
FORCEADD TAP..6
R 2
(-3025 1900);
FORCEPROP 3 LASTPIN (-3075 1900) SIG_NAME P5E_CPU1_P1_TX_DP<10>
J 0
(-3065 1910);
DISPLAY 0.659574 (-3065 1910);
PAINT MONO (-3065 1910);
DISPLAY INVISIBLE (-3065 1910);
FORCEPROP 1 LASTPIN (-3075 1900) BN 10
J 2
(-3023 1908);
DISPLAY 0.489362 (-3023 1908);
PAINT MONO (-3023 1908);
FORCEPROP 2 LAST BOM_COST IO_SLOT
J 0
(-3525 2000);
DISPLAY 0.829787 (-3525 2000);
DISPLAY INVISIBLE (-3525 2000);
FORCEPROP 2 LAST CDS_LIB standard
J 0
(-3025 1900);
DISPLAY INVISIBLE (-3025 1900);
FORCEPROP 1 LAST BODY_TYPE PLUMBING
J 2
(-3025 1850);
DISPLAY 0.702128 (-3025 1850);
PAINT GREEN (-3025 1850);
DISPLAY INVISIBLE (-3025 1850);
FORCEPROP 1 LAST HDL_TAP TRUE
J 2
(-3350 1775);
DISPLAY 0.702128 (-3350 1775);
PAINT GREEN (-3350 1775);
DISPLAY INVISIBLE (-3350 1775);
FORCEPROP 1 LAST PATH I213
J 2
(-3023 1900);
DISPLAY 0.872340 (-3023 1900);
PAINT GREEN (-3023 1900);
DISPLAY INVISIBLE (-3023 1900);
FORCEPROP 2 LAST ROOM RISER1
J 0
(-3525 1950);
DISPLAY 0.829787 (-3525 1950);
PAINT RED (-3525 1950);
DISPLAY INVISIBLE (-3525 1950);
FORCEADD TAP..6
R 2
(-3025 1800);
FORCEPROP 3 LASTPIN (-3075 1800) SIG_NAME P5E_CPU1_P1_TX_DP<11>
J 0
(-3065 1810);
DISPLAY 0.659574 (-3065 1810);
PAINT MONO (-3065 1810);
DISPLAY INVISIBLE (-3065 1810);
FORCEPROP 1 LASTPIN (-3075 1800) BN 11
J 2
(-3023 1808);
DISPLAY 0.489362 (-3023 1808);
PAINT MONO (-3023 1808);
FORCEPROP 2 LAST BOM_COST IO_SLOT
J 0
(-3525 1900);
DISPLAY 0.829787 (-3525 1900);
DISPLAY INVISIBLE (-3525 1900);
FORCEPROP 2 LAST CDS_LIB standard
J 0
(-3025 1800);
DISPLAY INVISIBLE (-3025 1800);
FORCEPROP 1 LAST BODY_TYPE PLUMBING
J 2
(-3025 1750);
DISPLAY 0.702128 (-3025 1750);
PAINT GREEN (-3025 1750);
DISPLAY INVISIBLE (-3025 1750);
FORCEPROP 1 LAST HDL_TAP TRUE
J 2
(-3350 1675);
DISPLAY 0.702128 (-3350 1675);
PAINT GREEN (-3350 1675);
DISPLAY INVISIBLE (-3350 1675);
FORCEPROP 1 LAST PATH I214
J 2
(-3023 1800);
DISPLAY 0.872340 (-3023 1800);
PAINT GREEN (-3023 1800);
DISPLAY INVISIBLE (-3023 1800);
FORCEPROP 2 LAST ROOM RISER1
J 0
(-3525 1850);
DISPLAY 0.829787 (-3525 1850);
PAINT RED (-3525 1850);
DISPLAY INVISIBLE (-3525 1850);
FORCEADD TAP..6
R 2
(-3025 1700);
FORCEPROP 3 LASTPIN (-3075 1700) SIG_NAME P5E_CPU1_P1_TX_DP<12>
J 0
(-3065 1710);
DISPLAY 0.659574 (-3065 1710);
PAINT MONO (-3065 1710);
DISPLAY INVISIBLE (-3065 1710);
FORCEPROP 1 LASTPIN (-3075 1700) BN 12
J 2
(-3023 1708);
DISPLAY 0.489362 (-3023 1708);
PAINT MONO (-3023 1708);
FORCEPROP 2 LAST BOM_COST IO_SLOT
J 0
(-3525 1800);
DISPLAY 0.829787 (-3525 1800);
DISPLAY INVISIBLE (-3525 1800);
FORCEPROP 2 LAST CDS_LIB standard
J 0
(-3025 1700);
DISPLAY INVISIBLE (-3025 1700);
FORCEPROP 1 LAST BODY_TYPE PLUMBING
J 2
(-3025 1650);
DISPLAY 0.702128 (-3025 1650);
PAINT GREEN (-3025 1650);
DISPLAY INVISIBLE (-3025 1650);
FORCEPROP 1 LAST HDL_TAP TRUE
J 2
(-3350 1575);
DISPLAY 0.702128 (-3350 1575);
PAINT GREEN (-3350 1575);
DISPLAY INVISIBLE (-3350 1575);
FORCEPROP 1 LAST PATH I215
J 2
(-3023 1700);
DISPLAY 0.872340 (-3023 1700);
PAINT GREEN (-3023 1700);
DISPLAY INVISIBLE (-3023 1700);
FORCEPROP 2 LAST ROOM RISER1
J 0
(-3525 1750);
DISPLAY 0.829787 (-3525 1750);
PAINT RED (-3525 1750);
DISPLAY INVISIBLE (-3525 1750);
FORCEADD TAP..6
R 2
(-3025 1600);
FORCEPROP 3 LASTPIN (-3075 1600) SIG_NAME P5E_CPU1_P1_TX_DP<13>
J 0
(-3065 1610);
DISPLAY 0.659574 (-3065 1610);
PAINT MONO (-3065 1610);
DISPLAY INVISIBLE (-3065 1610);
FORCEPROP 1 LASTPIN (-3075 1600) BN 13
J 2
(-3023 1608);
DISPLAY 0.489362 (-3023 1608);
PAINT MONO (-3023 1608);
FORCEPROP 2 LAST BOM_COST IO_SLOT
J 0
(-3525 1700);
DISPLAY 0.829787 (-3525 1700);
DISPLAY INVISIBLE (-3525 1700);
FORCEPROP 2 LAST CDS_LIB standard
J 0
(-3025 1600);
DISPLAY INVISIBLE (-3025 1600);
FORCEPROP 1 LAST BODY_TYPE PLUMBING
J 2
(-3025 1550);
DISPLAY 0.702128 (-3025 1550);
PAINT GREEN (-3025 1550);
DISPLAY INVISIBLE (-3025 1550);
FORCEPROP 1 LAST HDL_TAP TRUE
J 2
(-3350 1475);
DISPLAY 0.702128 (-3350 1475);
PAINT GREEN (-3350 1475);
DISPLAY INVISIBLE (-3350 1475);
FORCEPROP 1 LAST PATH I216
J 2
(-3023 1600);
DISPLAY 0.872340 (-3023 1600);
PAINT GREEN (-3023 1600);
DISPLAY INVISIBLE (-3023 1600);
FORCEPROP 2 LAST ROOM RISER1
J 0
(-3525 1650);
DISPLAY 0.829787 (-3525 1650);
PAINT RED (-3525 1650);
DISPLAY INVISIBLE (-3525 1650);
FORCEADD TAP..6
R 2
(-3025 1500);
FORCEPROP 3 LASTPIN (-3075 1500) SIG_NAME P5E_CPU1_P1_TX_DP<14>
J 0
(-3065 1510);
DISPLAY 0.659574 (-3065 1510);
PAINT MONO (-3065 1510);
DISPLAY INVISIBLE (-3065 1510);
FORCEPROP 1 LASTPIN (-3075 1500) BN 14
J 2
(-3023 1508);
DISPLAY 0.489362 (-3023 1508);
PAINT MONO (-3023 1508);
FORCEPROP 2 LAST BOM_COST IO_SLOT
J 0
(-3525 1600);
DISPLAY 0.829787 (-3525 1600);
DISPLAY INVISIBLE (-3525 1600);
FORCEPROP 2 LAST CDS_LIB standard
J 0
(-3025 1500);
DISPLAY INVISIBLE (-3025 1500);
FORCEPROP 1 LAST BODY_TYPE PLUMBING
J 2
(-3025 1450);
DISPLAY 0.702128 (-3025 1450);
PAINT GREEN (-3025 1450);
DISPLAY INVISIBLE (-3025 1450);
FORCEPROP 1 LAST HDL_TAP TRUE
J 2
(-3350 1375);
DISPLAY 0.702128 (-3350 1375);
PAINT GREEN (-3350 1375);
DISPLAY INVISIBLE (-3350 1375);
FORCEPROP 1 LAST PATH I217
J 2
(-3023 1500);
DISPLAY 0.872340 (-3023 1500);
PAINT GREEN (-3023 1500);
DISPLAY INVISIBLE (-3023 1500);
FORCEPROP 2 LAST ROOM RISER1
J 0
(-3525 1550);
DISPLAY 0.829787 (-3525 1550);
PAINT RED (-3525 1550);
DISPLAY INVISIBLE (-3525 1550);
FORCEADD TAP..6
R 2
(-3025 1400);
FORCEPROP 3 LASTPIN (-3075 1400) SIG_NAME P5E_CPU1_P1_TX_DP<15>
J 0
(-3065 1410);
DISPLAY 0.659574 (-3065 1410);
PAINT MONO (-3065 1410);
DISPLAY INVISIBLE (-3065 1410);
FORCEPROP 1 LASTPIN (-3075 1400) BN 15
J 2
(-3023 1408);
DISPLAY 0.489362 (-3023 1408);
PAINT MONO (-3023 1408);
FORCEPROP 2 LAST BOM_COST IO_SLOT
J 0
(-3525 1500);
DISPLAY 0.829787 (-3525 1500);
DISPLAY INVISIBLE (-3525 1500);
FORCEPROP 2 LAST CDS_LIB standard
J 0
(-3025 1400);
DISPLAY INVISIBLE (-3025 1400);
FORCEPROP 1 LAST BODY_TYPE PLUMBING
J 2
(-3025 1350);
DISPLAY 0.702128 (-3025 1350);
PAINT GREEN (-3025 1350);
DISPLAY INVISIBLE (-3025 1350);
FORCEPROP 1 LAST HDL_TAP TRUE
J 2
(-3350 1275);
DISPLAY 0.702128 (-3350 1275);
PAINT GREEN (-3350 1275);
DISPLAY INVISIBLE (-3350 1275);
FORCEPROP 1 LAST PATH I218
J 2
(-3023 1400);
DISPLAY 0.872340 (-3023 1400);
PAINT GREEN (-3023 1400);
DISPLAY INVISIBLE (-3023 1400);
FORCEPROP 2 LAST ROOM RISER1
J 0
(-3525 1450);
DISPLAY 0.829787 (-3525 1450);
PAINT RED (-3525 1450);
DISPLAY INVISIBLE (-3525 1450);
FORCEADD TAP..6
(-6450 5550);
FORCEPROP 3 LASTPIN (-6400 5550) SIG_NAME P5E_CPU1_P0_RX_DN<15>
J 0
(-6390 5560);
DISPLAY 0.659574 (-6390 5560);
PAINT MONO (-6390 5560);
DISPLAY INVISIBLE (-6390 5560);
FORCEPROP 1 LASTPIN (-6400 5550) BN 15
J 0
(-6452 5558);
DISPLAY 0.489362 (-6452 5558);
PAINT MONO (-6452 5558);
FORCEPROP 2 LAST CDS_LIB mstr_standard
J 0
(-6450 5550);
DISPLAY INVISIBLE (-6450 5550);
FORCEPROP 1 LAST BODY_TYPE PLUMBING
J 0
(-6450 5500);
DISPLAY 0.574468 (-6450 5500);
PAINT GREEN (-6450 5500);
DISPLAY INVISIBLE (-6450 5500);
FORCEPROP 1 LAST HDL_TAP TRUE
J 0
(-6125 5425);
DISPLAY 0.574468 (-6125 5425);
PAINT GREEN (-6125 5425);
DISPLAY INVISIBLE (-6125 5425);
FORCEPROP 1 LAST PATH I219
J 0
(-6452 5550);
DISPLAY 0.872340 (-6452 5550);
PAINT GREEN (-6452 5550);
DISPLAY INVISIBLE (-6452 5550);
FORCEADD TAP..6
(-6450 5350);
FORCEPROP 3 LASTPIN (-6400 5350) SIG_NAME P5E_CPU1_P0_RX_DN<13>
J 0
(-6390 5360);
DISPLAY 0.659574 (-6390 5360);
PAINT MONO (-6390 5360);
DISPLAY INVISIBLE (-6390 5360);
FORCEPROP 1 LASTPIN (-6400 5350) BN 13
J 0
(-6452 5358);
DISPLAY 0.489362 (-6452 5358);
PAINT MONO (-6452 5358);
FORCEPROP 2 LAST CDS_LIB mstr_standard
J 0
(-6450 5350);
DISPLAY INVISIBLE (-6450 5350);
FORCEPROP 1 LAST BODY_TYPE PLUMBING
J 0
(-6450 5300);
DISPLAY 0.574468 (-6450 5300);
PAINT GREEN (-6450 5300);
DISPLAY INVISIBLE (-6450 5300);
FORCEPROP 1 LAST HDL_TAP TRUE
J 0
(-6125 5225);
DISPLAY 0.574468 (-6125 5225);
PAINT GREEN (-6125 5225);
DISPLAY INVISIBLE (-6125 5225);
FORCEPROP 1 LAST PATH I220
J 0
(-6452 5350);
DISPLAY 0.872340 (-6452 5350);
PAINT GREEN (-6452 5350);
DISPLAY INVISIBLE (-6452 5350);
FORCEADD TAP..6
(-6450 5450);
FORCEPROP 3 LASTPIN (-6400 5450) SIG_NAME P5E_CPU1_P0_RX_DN<14>
J 0
(-6390 5460);
DISPLAY 0.659574 (-6390 5460);
PAINT MONO (-6390 5460);
DISPLAY INVISIBLE (-6390 5460);
FORCEPROP 1 LASTPIN (-6400 5450) BN 14
J 0
(-6452 5458);
DISPLAY 0.489362 (-6452 5458);
PAINT MONO (-6452 5458);
FORCEPROP 2 LAST CDS_LIB mstr_standard
J 0
(-6450 5450);
DISPLAY INVISIBLE (-6450 5450);
FORCEPROP 1 LAST BODY_TYPE PLUMBING
J 0
(-6450 5400);
DISPLAY 0.574468 (-6450 5400);
PAINT GREEN (-6450 5400);
DISPLAY INVISIBLE (-6450 5400);
FORCEPROP 1 LAST HDL_TAP TRUE
J 0
(-6125 5325);
DISPLAY 0.574468 (-6125 5325);
PAINT GREEN (-6125 5325);
DISPLAY INVISIBLE (-6125 5325);
FORCEPROP 1 LAST PATH I221
J 0
(-6452 5450);
DISPLAY 0.872340 (-6452 5450);
PAINT GREEN (-6452 5450);
DISPLAY INVISIBLE (-6452 5450);
FORCEADD TAP..6
(-6450 5250);
FORCEPROP 3 LASTPIN (-6400 5250) SIG_NAME P5E_CPU1_P0_RX_DN<12>
J 0
(-6390 5260);
DISPLAY 0.659574 (-6390 5260);
PAINT MONO (-6390 5260);
DISPLAY INVISIBLE (-6390 5260);
FORCEPROP 1 LASTPIN (-6400 5250) BN 12
J 0
(-6452 5258);
DISPLAY 0.489362 (-6452 5258);
PAINT MONO (-6452 5258);
FORCEPROP 2 LAST CDS_LIB standard
J 0
(-6450 5250);
DISPLAY INVISIBLE (-6450 5250);
FORCEPROP 1 LAST BODY_TYPE PLUMBING
J 0
(-6450 5200);
DISPLAY 0.574468 (-6450 5200);
PAINT GREEN (-6450 5200);
DISPLAY INVISIBLE (-6450 5200);
FORCEPROP 1 LAST HDL_TAP TRUE
J 0
(-6125 5125);
DISPLAY 0.574468 (-6125 5125);
PAINT GREEN (-6125 5125);
DISPLAY INVISIBLE (-6125 5125);
FORCEPROP 1 LAST PATH I222
J 0
(-6452 5250);
DISPLAY 0.872340 (-6452 5250);
PAINT GREEN (-6452 5250);
DISPLAY INVISIBLE (-6452 5250);
FORCEADD TAP..6
(-6450 5150);
FORCEPROP 3 LASTPIN (-6400 5150) SIG_NAME P5E_CPU1_P0_RX_DN<11>
J 0
(-6390 5160);
DISPLAY 0.659574 (-6390 5160);
PAINT MONO (-6390 5160);
DISPLAY INVISIBLE (-6390 5160);
FORCEPROP 1 LASTPIN (-6400 5150) BN 11
J 0
(-6452 5158);
DISPLAY 0.489362 (-6452 5158);
PAINT MONO (-6452 5158);
FORCEPROP 2 LAST CDS_LIB standard
J 0
(-6450 5150);
DISPLAY INVISIBLE (-6450 5150);
FORCEPROP 1 LAST BODY_TYPE PLUMBING
J 0
(-6450 5100);
DISPLAY 0.574468 (-6450 5100);
PAINT GREEN (-6450 5100);
DISPLAY INVISIBLE (-6450 5100);
FORCEPROP 1 LAST HDL_TAP TRUE
J 0
(-6125 5025);
DISPLAY 0.574468 (-6125 5025);
PAINT GREEN (-6125 5025);
DISPLAY INVISIBLE (-6125 5025);
FORCEPROP 1 LAST PATH I223
J 0
(-6452 5150);
DISPLAY 0.872340 (-6452 5150);
PAINT GREEN (-6452 5150);
DISPLAY INVISIBLE (-6452 5150);
FORCEADD TAP..6
(-6450 5050);
FORCEPROP 3 LASTPIN (-6400 5050) SIG_NAME P5E_CPU1_P0_RX_DN<10>
J 0
(-6390 5060);
DISPLAY 0.659574 (-6390 5060);
PAINT MONO (-6390 5060);
DISPLAY INVISIBLE (-6390 5060);
FORCEPROP 1 LASTPIN (-6400 5050) BN 10
J 0
(-6452 5058);
DISPLAY 0.489362 (-6452 5058);
PAINT MONO (-6452 5058);
FORCEPROP 2 LAST CDS_LIB standard
J 0
(-6450 5050);
DISPLAY INVISIBLE (-6450 5050);
FORCEPROP 1 LAST BODY_TYPE PLUMBING
J 0
(-6450 5000);
DISPLAY 0.574468 (-6450 5000);
PAINT GREEN (-6450 5000);
DISPLAY INVISIBLE (-6450 5000);
FORCEPROP 1 LAST HDL_TAP TRUE
J 0
(-6125 4925);
DISPLAY 0.574468 (-6125 4925);
PAINT GREEN (-6125 4925);
DISPLAY INVISIBLE (-6125 4925);
FORCEPROP 1 LAST PATH I228
J 0
(-6452 5050);
DISPLAY 0.872340 (-6452 5050);
PAINT GREEN (-6452 5050);
DISPLAY INVISIBLE (-6452 5050);
FORCEADD TAP..6
(-6450 4850);
FORCEPROP 3 LASTPIN (-6400 4850) SIG_NAME P5E_CPU1_P0_RX_DN<8>
J 0
(-6390 4860);
DISPLAY 0.659574 (-6390 4860);
PAINT MONO (-6390 4860);
DISPLAY INVISIBLE (-6390 4860);
FORCEPROP 1 LASTPIN (-6400 4850) BN 8
J 0
(-6452 4858);
DISPLAY 0.489362 (-6452 4858);
PAINT MONO (-6452 4858);
FORCEPROP 2 LAST CDS_LIB standard
J 0
(-6450 4850);
DISPLAY INVISIBLE (-6450 4850);
FORCEPROP 1 LAST BODY_TYPE PLUMBING
J 0
(-6450 4800);
DISPLAY 0.574468 (-6450 4800);
PAINT GREEN (-6450 4800);
DISPLAY INVISIBLE (-6450 4800);
FORCEPROP 1 LAST HDL_TAP TRUE
J 0
(-6125 4725);
DISPLAY 0.574468 (-6125 4725);
PAINT GREEN (-6125 4725);
DISPLAY INVISIBLE (-6125 4725);
FORCEPROP 1 LAST PATH I229
J 0
(-6452 4850);
DISPLAY 0.872340 (-6452 4850);
PAINT GREEN (-6452 4850);
DISPLAY INVISIBLE (-6452 4850);
FORCEADD TAP..6
(-6450 4950);
FORCEPROP 3 LASTPIN (-6400 4950) SIG_NAME P5E_CPU1_P0_RX_DN<9>
J 0
(-6390 4960);
DISPLAY 0.659574 (-6390 4960);
PAINT MONO (-6390 4960);
DISPLAY INVISIBLE (-6390 4960);
FORCEPROP 1 LASTPIN (-6400 4950) BN 9
J 0
(-6452 4958);
DISPLAY 0.489362 (-6452 4958);
PAINT MONO (-6452 4958);
FORCEPROP 2 LAST CDS_LIB standard
J 0
(-6450 4950);
DISPLAY INVISIBLE (-6450 4950);
FORCEPROP 1 LAST BODY_TYPE PLUMBING
J 0
(-6450 4900);
DISPLAY 0.574468 (-6450 4900);
PAINT GREEN (-6450 4900);
DISPLAY INVISIBLE (-6450 4900);
FORCEPROP 1 LAST HDL_TAP TRUE
J 0
(-6125 4825);
DISPLAY 0.574468 (-6125 4825);
PAINT GREEN (-6125 4825);
DISPLAY INVISIBLE (-6125 4825);
FORCEPROP 1 LAST PATH I230
J 0
(-6452 4950);
DISPLAY 0.872340 (-6452 4950);
PAINT GREEN (-6452 4950);
DISPLAY INVISIBLE (-6452 4950);
FORCEADD TAP..6
(-6450 4750);
FORCEPROP 3 LASTPIN (-6400 4750) SIG_NAME P5E_CPU1_P0_RX_DN<7>
J 0
(-6390 4760);
DISPLAY 0.659574 (-6390 4760);
PAINT MONO (-6390 4760);
DISPLAY INVISIBLE (-6390 4760);
FORCEPROP 1 LASTPIN (-6400 4750) BN 7
J 0
(-6452 4758);
DISPLAY 0.489362 (-6452 4758);
PAINT MONO (-6452 4758);
FORCEPROP 2 LAST CDS_LIB standard
J 0
(-6450 4750);
DISPLAY INVISIBLE (-6450 4750);
FORCEPROP 1 LAST BODY_TYPE PLUMBING
J 0
(-6450 4700);
DISPLAY 0.574468 (-6450 4700);
PAINT GREEN (-6450 4700);
DISPLAY INVISIBLE (-6450 4700);
FORCEPROP 1 LAST HDL_TAP TRUE
J 0
(-6125 4625);
DISPLAY 0.574468 (-6125 4625);
PAINT GREEN (-6125 4625);
DISPLAY INVISIBLE (-6125 4625);
FORCEPROP 1 LAST PATH I231
J 0
(-6452 4750);
DISPLAY 0.872340 (-6452 4750);
PAINT GREEN (-6452 4750);
DISPLAY INVISIBLE (-6452 4750);
FORCEADD TAP..6
(-6450 4650);
FORCEPROP 3 LASTPIN (-6400 4650) SIG_NAME P5E_CPU1_P0_RX_DN<6>
J 0
(-6390 4660);
DISPLAY 0.659574 (-6390 4660);
PAINT MONO (-6390 4660);
DISPLAY INVISIBLE (-6390 4660);
FORCEPROP 1 LASTPIN (-6400 4650) BN 6
J 0
(-6452 4658);
DISPLAY 0.489362 (-6452 4658);
PAINT MONO (-6452 4658);
FORCEPROP 2 LAST CDS_LIB standard
J 0
(-6450 4650);
DISPLAY INVISIBLE (-6450 4650);
FORCEPROP 1 LAST BODY_TYPE PLUMBING
J 0
(-6450 4600);
DISPLAY 0.574468 (-6450 4600);
PAINT GREEN (-6450 4600);
DISPLAY INVISIBLE (-6450 4600);
FORCEPROP 1 LAST HDL_TAP TRUE
J 0
(-6125 4525);
DISPLAY 0.574468 (-6125 4525);
PAINT GREEN (-6125 4525);
DISPLAY INVISIBLE (-6125 4525);
FORCEPROP 1 LAST PATH I232
J 0
(-6452 4650);
DISPLAY 0.872340 (-6452 4650);
PAINT GREEN (-6452 4650);
DISPLAY INVISIBLE (-6452 4650);
FORCEADD TAP..6
(-6450 4450);
FORCEPROP 3 LASTPIN (-6400 4450) SIG_NAME P5E_CPU1_P0_RX_DN<4>
J 0
(-6390 4460);
DISPLAY 0.659574 (-6390 4460);
PAINT MONO (-6390 4460);
DISPLAY INVISIBLE (-6390 4460);
FORCEPROP 1 LASTPIN (-6400 4450) BN 4
J 0
(-6452 4458);
DISPLAY 0.489362 (-6452 4458);
PAINT MONO (-6452 4458);
FORCEPROP 2 LAST CDS_LIB standard
J 0
(-6450 4450);
DISPLAY INVISIBLE (-6450 4450);
FORCEPROP 1 LAST BODY_TYPE PLUMBING
J 0
(-6450 4400);
DISPLAY 0.574468 (-6450 4400);
PAINT GREEN (-6450 4400);
DISPLAY INVISIBLE (-6450 4400);
FORCEPROP 1 LAST HDL_TAP TRUE
J 0
(-6125 4325);
DISPLAY 0.574468 (-6125 4325);
PAINT GREEN (-6125 4325);
DISPLAY INVISIBLE (-6125 4325);
FORCEPROP 1 LAST PATH I238
J 0
(-6452 4450);
DISPLAY 0.872340 (-6452 4450);
PAINT GREEN (-6452 4450);
DISPLAY INVISIBLE (-6452 4450);
FORCEADD TAP..6
(-6450 4550);
FORCEPROP 3 LASTPIN (-6400 4550) SIG_NAME P5E_CPU1_P0_RX_DN<5>
J 0
(-6390 4560);
DISPLAY 0.659574 (-6390 4560);
PAINT MONO (-6390 4560);
DISPLAY INVISIBLE (-6390 4560);
FORCEPROP 1 LASTPIN (-6400 4550) BN 5
J 0
(-6452 4558);
DISPLAY 0.489362 (-6452 4558);
PAINT MONO (-6452 4558);
FORCEPROP 2 LAST CDS_LIB standard
J 0
(-6450 4550);
DISPLAY INVISIBLE (-6450 4550);
FORCEPROP 1 LAST BODY_TYPE PLUMBING
J 0
(-6450 4500);
DISPLAY 0.574468 (-6450 4500);
PAINT GREEN (-6450 4500);
DISPLAY INVISIBLE (-6450 4500);
FORCEPROP 1 LAST HDL_TAP TRUE
J 0
(-6125 4425);
DISPLAY 0.574468 (-6125 4425);
PAINT GREEN (-6125 4425);
DISPLAY INVISIBLE (-6125 4425);
FORCEPROP 1 LAST PATH I239
J 0
(-6452 4550);
DISPLAY 0.872340 (-6452 4550);
PAINT GREEN (-6452 4550);
DISPLAY INVISIBLE (-6452 4550);
FORCEADD TAP..6
(-6450 4350);
FORCEPROP 3 LASTPIN (-6400 4350) SIG_NAME P5E_CPU1_P0_RX_DN<3>
J 0
(-6390 4360);
DISPLAY 0.659574 (-6390 4360);
PAINT MONO (-6390 4360);
DISPLAY INVISIBLE (-6390 4360);
FORCEPROP 1 LASTPIN (-6400 4350) BN 3
J 0
(-6452 4358);
DISPLAY 0.489362 (-6452 4358);
PAINT MONO (-6452 4358);
FORCEPROP 2 LAST CDS_LIB standard
J 0
(-6450 4350);
DISPLAY INVISIBLE (-6450 4350);
FORCEPROP 1 LAST BODY_TYPE PLUMBING
J 0
(-6450 4300);
DISPLAY 0.574468 (-6450 4300);
PAINT GREEN (-6450 4300);
DISPLAY INVISIBLE (-6450 4300);
FORCEPROP 1 LAST HDL_TAP TRUE
J 0
(-6125 4225);
DISPLAY 0.574468 (-6125 4225);
PAINT GREEN (-6125 4225);
DISPLAY INVISIBLE (-6125 4225);
FORCEPROP 1 LAST PATH I240
J 0
(-6452 4350);
DISPLAY 0.872340 (-6452 4350);
PAINT GREEN (-6452 4350);
DISPLAY INVISIBLE (-6452 4350);
FORCEADD TAP..6
(-6450 4250);
FORCEPROP 3 LASTPIN (-6400 4250) SIG_NAME P5E_CPU1_P0_RX_DN<2>
J 0
(-6390 4260);
DISPLAY 0.659574 (-6390 4260);
PAINT MONO (-6390 4260);
DISPLAY INVISIBLE (-6390 4260);
FORCEPROP 1 LASTPIN (-6400 4250) BN 2
J 0
(-6452 4258);
DISPLAY 0.489362 (-6452 4258);
PAINT MONO (-6452 4258);
FORCEPROP 2 LAST CDS_LIB standard
J 0
(-6450 4250);
DISPLAY INVISIBLE (-6450 4250);
FORCEPROP 1 LAST BODY_TYPE PLUMBING
J 0
(-6450 4200);
DISPLAY 0.574468 (-6450 4200);
PAINT GREEN (-6450 4200);
DISPLAY INVISIBLE (-6450 4200);
FORCEPROP 1 LAST HDL_TAP TRUE
J 0
(-6125 4125);
DISPLAY 0.574468 (-6125 4125);
PAINT GREEN (-6125 4125);
DISPLAY INVISIBLE (-6125 4125);
FORCEPROP 1 LAST PATH I241
J 0
(-6452 4250);
DISPLAY 0.872340 (-6452 4250);
PAINT GREEN (-6452 4250);
DISPLAY INVISIBLE (-6452 4250);
FORCEADD TAP..6
(-6450 4150);
FORCEPROP 3 LASTPIN (-6400 4150) SIG_NAME P5E_CPU1_P0_RX_DN<1>
J 0
(-6390 4160);
DISPLAY 0.659574 (-6390 4160);
PAINT MONO (-6390 4160);
DISPLAY INVISIBLE (-6390 4160);
FORCEPROP 1 LASTPIN (-6400 4150) BN 1
J 0
(-6452 4158);
DISPLAY 0.489362 (-6452 4158);
PAINT MONO (-6452 4158);
FORCEPROP 2 LAST CDS_LIB standard
J 0
(-6450 4150);
DISPLAY INVISIBLE (-6450 4150);
FORCEPROP 1 LAST BODY_TYPE PLUMBING
J 0
(-6450 4100);
DISPLAY 0.574468 (-6450 4100);
PAINT GREEN (-6450 4100);
DISPLAY INVISIBLE (-6450 4100);
FORCEPROP 1 LAST HDL_TAP TRUE
J 0
(-6125 4025);
DISPLAY 0.574468 (-6125 4025);
PAINT GREEN (-6125 4025);
DISPLAY INVISIBLE (-6125 4025);
FORCEPROP 1 LAST PATH I242
J 0
(-6452 4150);
DISPLAY 0.872340 (-6452 4150);
PAINT GREEN (-6452 4150);
DISPLAY INVISIBLE (-6452 4150);
FORCEADD OFFPAGE..1
(-7550 5775);
FORCEPROP 2 LAST $XR0 116 
J 0
(-7802 5775);
DISPLAY 0.638298 (-7802 5775);
PAINT MONO (-7802 5775);
FORCEPROP 2 LAST CDS_LIB standard
J 0
(-7550 5775);
DISPLAY INVISIBLE (-7550 5775);
FORCEPROP 1 LAST OFFPAGE TRUE
J 0
(-7225 5650);
DISPLAY 0.872340 (-7225 5650);
PAINT GREEN (-7225 5650);
DISPLAY INVISIBLE (-7225 5650);
FORCEPROP 1 LAST COMMENT_BODY TRUE
J 0
(-7425 5675);
DISPLAY 0.872340 (-7425 5675);
PAINT GREEN (-7425 5675);
DISPLAY INVISIBLE (-7425 5675);
FORCEPROP 2 LAST PATH I249
J 0
(-7800 5825);
DISPLAY 1.021277 (-7800 5825);
DISPLAY INVISIBLE (-7800 5825);
FORCEADD TAP..6
(-6450 4050);
FORCEPROP 3 LASTPIN (-6400 4050) SIG_NAME P5E_CPU1_P0_RX_DN<0>
J 0
(-6390 4060);
DISPLAY 0.659574 (-6390 4060);
PAINT MONO (-6390 4060);
DISPLAY INVISIBLE (-6390 4060);
FORCEPROP 1 LASTPIN (-6400 4050) BN 0
J 0
(-6452 4058);
DISPLAY 0.489362 (-6452 4058);
PAINT MONO (-6452 4058);
FORCEPROP 2 LAST CDS_LIB standard
J 0
(-6450 4050);
DISPLAY INVISIBLE (-6450 4050);
FORCEPROP 1 LAST BODY_TYPE PLUMBING
J 0
(-6450 4000);
DISPLAY 0.574468 (-6450 4000);
PAINT GREEN (-6450 4000);
DISPLAY INVISIBLE (-6450 4000);
FORCEPROP 1 LAST HDL_TAP TRUE
J 0
(-6125 3925);
DISPLAY 0.574468 (-6125 3925);
PAINT GREEN (-6125 3925);
DISPLAY INVISIBLE (-6125 3925);
FORCEPROP 1 LAST PATH I253
J 0
(-6452 4050);
DISPLAY 0.872340 (-6452 4050);
PAINT GREEN (-6452 4050);
DISPLAY INVISIBLE (-6452 4050);
FORCEADD TAP..6
(-6450 2600);
FORCEPROP 3 LASTPIN (-6400 2600) SIG_NAME P5E_CPU1_P1_RX_DP<3>
J 0
(-6390 2610);
DISPLAY 0.659574 (-6390 2610);
PAINT MONO (-6390 2610);
DISPLAY INVISIBLE (-6390 2610);
FORCEPROP 1 LASTPIN (-6400 2600) BN 3
J 0
(-6452 2608);
DISPLAY 0.489362 (-6452 2608);
PAINT MONO (-6452 2608);
FORCEPROP 2 LAST CDS_LIB standard
J 0
(-6450 2600);
DISPLAY INVISIBLE (-6450 2600);
FORCEPROP 1 LAST BODY_TYPE PLUMBING
J 0
(-6450 2550);
DISPLAY 0.574468 (-6450 2550);
PAINT GREEN (-6450 2550);
DISPLAY INVISIBLE (-6450 2550);
FORCEPROP 1 LAST HDL_TAP TRUE
J 0
(-6125 2475);
DISPLAY 0.574468 (-6125 2475);
PAINT GREEN (-6125 2475);
DISPLAY INVISIBLE (-6125 2475);
FORCEPROP 1 LAST PATH I255
J 0
(-6452 2600);
DISPLAY 0.872340 (-6452 2600);
PAINT GREEN (-6452 2600);
DISPLAY INVISIBLE (-6452 2600);
FORCEADD TAP..6
(-6450 2700);
FORCEPROP 3 LASTPIN (-6400 2700) SIG_NAME P5E_CPU1_P1_RX_DP<2>
J 0
(-6390 2710);
DISPLAY 0.659574 (-6390 2710);
PAINT MONO (-6390 2710);
DISPLAY INVISIBLE (-6390 2710);
FORCEPROP 1 LASTPIN (-6400 2700) BN 2
J 0
(-6452 2708);
DISPLAY 0.489362 (-6452 2708);
PAINT MONO (-6452 2708);
FORCEPROP 2 LAST CDS_LIB mstr_standard
J 0
(-6450 2700);
DISPLAY INVISIBLE (-6450 2700);
FORCEPROP 1 LAST BODY_TYPE PLUMBING
J 0
(-6450 2650);
DISPLAY 0.574468 (-6450 2650);
PAINT GREEN (-6450 2650);
DISPLAY INVISIBLE (-6450 2650);
FORCEPROP 1 LAST HDL_TAP TRUE
J 0
(-6125 2575);
DISPLAY 0.574468 (-6125 2575);
PAINT GREEN (-6125 2575);
DISPLAY INVISIBLE (-6125 2575);
FORCEPROP 1 LAST PATH I256
J 0
(-6452 2700);
DISPLAY 0.872340 (-6452 2700);
PAINT GREEN (-6452 2700);
DISPLAY INVISIBLE (-6452 2700);
FORCEADD TAP..6
(-6450 2900);
FORCEPROP 3 LASTPIN (-6400 2900) SIG_NAME P5E_CPU1_P1_RX_DP<0>
J 0
(-6390 2910);
DISPLAY 0.659574 (-6390 2910);
PAINT MONO (-6390 2910);
DISPLAY INVISIBLE (-6390 2910);
FORCEPROP 1 LASTPIN (-6400 2900) BN 0
J 0
(-6452 2908);
DISPLAY 0.489362 (-6452 2908);
PAINT MONO (-6452 2908);
FORCEPROP 2 LAST CDS_LIB mstr_standard
J 0
(-6450 2900);
DISPLAY INVISIBLE (-6450 2900);
FORCEPROP 1 LAST BODY_TYPE PLUMBING
J 0
(-6450 2850);
DISPLAY 0.574468 (-6450 2850);
PAINT GREEN (-6450 2850);
DISPLAY INVISIBLE (-6450 2850);
FORCEPROP 1 LAST HDL_TAP TRUE
J 0
(-6125 2775);
DISPLAY 0.574468 (-6125 2775);
PAINT GREEN (-6125 2775);
DISPLAY INVISIBLE (-6125 2775);
FORCEPROP 1 LAST PATH I257
J 0
(-6452 2900);
DISPLAY 0.872340 (-6452 2900);
PAINT GREEN (-6452 2900);
DISPLAY INVISIBLE (-6452 2900);
FORCEADD TAP..6
(-6450 2800);
FORCEPROP 3 LASTPIN (-6400 2800) SIG_NAME P5E_CPU1_P1_RX_DP<1>
J 0
(-6390 2810);
DISPLAY 0.659574 (-6390 2810);
PAINT MONO (-6390 2810);
DISPLAY INVISIBLE (-6390 2810);
FORCEPROP 1 LASTPIN (-6400 2800) BN 1
J 0
(-6452 2808);
DISPLAY 0.489362 (-6452 2808);
PAINT MONO (-6452 2808);
FORCEPROP 2 LAST CDS_LIB mstr_standard
J 0
(-6450 2800);
DISPLAY INVISIBLE (-6450 2800);
FORCEPROP 1 LAST BODY_TYPE PLUMBING
J 0
(-6450 2750);
DISPLAY 0.574468 (-6450 2750);
PAINT GREEN (-6450 2750);
DISPLAY INVISIBLE (-6450 2750);
FORCEPROP 1 LAST HDL_TAP TRUE
J 0
(-6125 2675);
DISPLAY 0.574468 (-6125 2675);
PAINT GREEN (-6125 2675);
DISPLAY INVISIBLE (-6125 2675);
FORCEPROP 1 LAST PATH I258
J 0
(-6452 2800);
DISPLAY 0.872340 (-6452 2800);
PAINT GREEN (-6452 2800);
DISPLAY INVISIBLE (-6452 2800);
FORCEADD TAP..6
(-6600 2850);
FORCEPROP 3 LASTPIN (-6550 2850) SIG_NAME P5E_CPU1_P1_RX_DN<0>
J 0
(-6540 2860);
DISPLAY 0.659574 (-6540 2860);
PAINT MONO (-6540 2860);
DISPLAY INVISIBLE (-6540 2860);
FORCEPROP 1 LASTPIN (-6550 2850) BN 0
J 0
(-6602 2858);
DISPLAY 0.489362 (-6602 2858);
PAINT MONO (-6602 2858);
FORCEPROP 2 LAST CDS_LIB mstr_standard
J 0
(-6600 2850);
DISPLAY INVISIBLE (-6600 2850);
FORCEPROP 1 LAST BODY_TYPE PLUMBING
J 0
(-6600 2800);
DISPLAY 0.574468 (-6600 2800);
PAINT GREEN (-6600 2800);
DISPLAY INVISIBLE (-6600 2800);
FORCEPROP 1 LAST HDL_TAP TRUE
J 0
(-6275 2725);
DISPLAY 0.574468 (-6275 2725);
PAINT GREEN (-6275 2725);
DISPLAY INVISIBLE (-6275 2725);
FORCEPROP 1 LAST PATH I259
J 0
(-6602 2850);
DISPLAY 0.872340 (-6602 2850);
PAINT GREEN (-6602 2850);
DISPLAY INVISIBLE (-6602 2850);
FORCEADD TAP..6
(-6600 2750);
FORCEPROP 3 LASTPIN (-6550 2750) SIG_NAME P5E_CPU1_P1_RX_DN<1>
J 0
(-6540 2760);
DISPLAY 0.659574 (-6540 2760);
PAINT MONO (-6540 2760);
DISPLAY INVISIBLE (-6540 2760);
FORCEPROP 1 LASTPIN (-6550 2750) BN 1
J 0
(-6602 2758);
DISPLAY 0.489362 (-6602 2758);
PAINT MONO (-6602 2758);
FORCEPROP 2 LAST CDS_LIB mstr_standard
J 0
(-6600 2750);
DISPLAY INVISIBLE (-6600 2750);
FORCEPROP 1 LAST BODY_TYPE PLUMBING
J 0
(-6600 2700);
DISPLAY 0.574468 (-6600 2700);
PAINT GREEN (-6600 2700);
DISPLAY INVISIBLE (-6600 2700);
FORCEPROP 1 LAST HDL_TAP TRUE
J 0
(-6275 2625);
DISPLAY 0.574468 (-6275 2625);
PAINT GREEN (-6275 2625);
DISPLAY INVISIBLE (-6275 2625);
FORCEPROP 1 LAST PATH I260
J 0
(-6602 2750);
DISPLAY 0.872340 (-6602 2750);
PAINT GREEN (-6602 2750);
DISPLAY INVISIBLE (-6602 2750);
FORCEADD TAP..6
(-6600 2650);
FORCEPROP 3 LASTPIN (-6550 2650) SIG_NAME P5E_CPU1_P1_RX_DN<2>
J 0
(-6540 2660);
DISPLAY 0.659574 (-6540 2660);
PAINT MONO (-6540 2660);
DISPLAY INVISIBLE (-6540 2660);
FORCEPROP 1 LASTPIN (-6550 2650) BN 2
J 0
(-6602 2658);
DISPLAY 0.489362 (-6602 2658);
PAINT MONO (-6602 2658);
FORCEPROP 2 LAST CDS_LIB standard
J 0
(-6600 2650);
DISPLAY INVISIBLE (-6600 2650);
FORCEPROP 1 LAST BODY_TYPE PLUMBING
J 0
(-6600 2600);
DISPLAY 0.574468 (-6600 2600);
PAINT GREEN (-6600 2600);
DISPLAY INVISIBLE (-6600 2600);
FORCEPROP 1 LAST HDL_TAP TRUE
J 0
(-6275 2525);
DISPLAY 0.574468 (-6275 2525);
PAINT GREEN (-6275 2525);
DISPLAY INVISIBLE (-6275 2525);
FORCEPROP 1 LAST PATH I261
J 0
(-6602 2650);
DISPLAY 0.872340 (-6602 2650);
PAINT GREEN (-6602 2650);
DISPLAY INVISIBLE (-6602 2650);
FORCEADD TAP..6
(-6450 2100);
FORCEPROP 3 LASTPIN (-6400 2100) SIG_NAME P5E_CPU1_P1_RX_DP<8>
J 0
(-6390 2110);
DISPLAY 0.659574 (-6390 2110);
PAINT MONO (-6390 2110);
DISPLAY INVISIBLE (-6390 2110);
FORCEPROP 1 LASTPIN (-6400 2100) BN 8
J 0
(-6452 2108);
DISPLAY 0.489362 (-6452 2108);
PAINT MONO (-6452 2108);
FORCEPROP 2 LAST CDS_LIB standard
J 0
(-6450 2100);
DISPLAY INVISIBLE (-6450 2100);
FORCEPROP 1 LAST BODY_TYPE PLUMBING
J 0
(-6450 2050);
DISPLAY 0.574468 (-6450 2050);
PAINT GREEN (-6450 2050);
DISPLAY INVISIBLE (-6450 2050);
FORCEPROP 1 LAST HDL_TAP TRUE
J 0
(-6125 1975);
DISPLAY 0.574468 (-6125 1975);
PAINT GREEN (-6125 1975);
DISPLAY INVISIBLE (-6125 1975);
FORCEPROP 1 LAST PATH I262
J 0
(-6452 2100);
DISPLAY 0.872340 (-6452 2100);
PAINT GREEN (-6452 2100);
DISPLAY INVISIBLE (-6452 2100);
FORCEADD TAP..6
(-6450 2200);
FORCEPROP 3 LASTPIN (-6400 2200) SIG_NAME P5E_CPU1_P1_RX_DP<7>
J 0
(-6390 2210);
DISPLAY 0.659574 (-6390 2210);
PAINT MONO (-6390 2210);
DISPLAY INVISIBLE (-6390 2210);
FORCEPROP 1 LASTPIN (-6400 2200) BN 7
J 0
(-6452 2208);
DISPLAY 0.489362 (-6452 2208);
PAINT MONO (-6452 2208);
FORCEPROP 2 LAST CDS_LIB standard
J 0
(-6450 2200);
DISPLAY INVISIBLE (-6450 2200);
FORCEPROP 1 LAST BODY_TYPE PLUMBING
J 0
(-6450 2150);
DISPLAY 0.574468 (-6450 2150);
PAINT GREEN (-6450 2150);
DISPLAY INVISIBLE (-6450 2150);
FORCEPROP 1 LAST HDL_TAP TRUE
J 0
(-6125 2075);
DISPLAY 0.574468 (-6125 2075);
PAINT GREEN (-6125 2075);
DISPLAY INVISIBLE (-6125 2075);
FORCEPROP 1 LAST PATH I263
J 0
(-6452 2200);
DISPLAY 0.872340 (-6452 2200);
PAINT GREEN (-6452 2200);
DISPLAY INVISIBLE (-6452 2200);
FORCEADD TAP..6
(-6450 2300);
FORCEPROP 3 LASTPIN (-6400 2300) SIG_NAME P5E_CPU1_P1_RX_DP<6>
J 0
(-6390 2310);
DISPLAY 0.659574 (-6390 2310);
PAINT MONO (-6390 2310);
DISPLAY INVISIBLE (-6390 2310);
FORCEPROP 1 LASTPIN (-6400 2300) BN 6
J 0
(-6452 2308);
DISPLAY 0.489362 (-6452 2308);
PAINT MONO (-6452 2308);
FORCEPROP 2 LAST CDS_LIB standard
J 0
(-6450 2300);
DISPLAY INVISIBLE (-6450 2300);
FORCEPROP 1 LAST BODY_TYPE PLUMBING
J 0
(-6450 2250);
DISPLAY 0.574468 (-6450 2250);
PAINT GREEN (-6450 2250);
DISPLAY INVISIBLE (-6450 2250);
FORCEPROP 1 LAST HDL_TAP TRUE
J 0
(-6125 2175);
DISPLAY 0.574468 (-6125 2175);
PAINT GREEN (-6125 2175);
DISPLAY INVISIBLE (-6125 2175);
FORCEPROP 1 LAST PATH I264
J 0
(-6452 2300);
DISPLAY 0.872340 (-6452 2300);
PAINT GREEN (-6452 2300);
DISPLAY INVISIBLE (-6452 2300);
FORCEADD TAP..6
(-6450 2500);
FORCEPROP 3 LASTPIN (-6400 2500) SIG_NAME P5E_CPU1_P1_RX_DP<4>
J 0
(-6390 2510);
DISPLAY 0.659574 (-6390 2510);
PAINT MONO (-6390 2510);
DISPLAY INVISIBLE (-6390 2510);
FORCEPROP 1 LASTPIN (-6400 2500) BN 4
J 0
(-6452 2508);
DISPLAY 0.489362 (-6452 2508);
PAINT MONO (-6452 2508);
FORCEPROP 2 LAST CDS_LIB standard
J 0
(-6450 2500);
DISPLAY INVISIBLE (-6450 2500);
FORCEPROP 1 LAST BODY_TYPE PLUMBING
J 0
(-6450 2450);
DISPLAY 0.574468 (-6450 2450);
PAINT GREEN (-6450 2450);
DISPLAY INVISIBLE (-6450 2450);
FORCEPROP 1 LAST HDL_TAP TRUE
J 0
(-6125 2375);
DISPLAY 0.574468 (-6125 2375);
PAINT GREEN (-6125 2375);
DISPLAY INVISIBLE (-6125 2375);
FORCEPROP 1 LAST PATH I265
J 0
(-6452 2500);
DISPLAY 0.872340 (-6452 2500);
PAINT GREEN (-6452 2500);
DISPLAY INVISIBLE (-6452 2500);
FORCEADD TAP..6
(-6450 2400);
FORCEPROP 3 LASTPIN (-6400 2400) SIG_NAME P5E_CPU1_P1_RX_DP<5>
J 0
(-6390 2410);
DISPLAY 0.659574 (-6390 2410);
PAINT MONO (-6390 2410);
DISPLAY INVISIBLE (-6390 2410);
FORCEPROP 1 LASTPIN (-6400 2400) BN 5
J 0
(-6452 2408);
DISPLAY 0.489362 (-6452 2408);
PAINT MONO (-6452 2408);
FORCEPROP 2 LAST CDS_LIB standard
J 0
(-6450 2400);
DISPLAY INVISIBLE (-6450 2400);
FORCEPROP 1 LAST BODY_TYPE PLUMBING
J 0
(-6450 2350);
DISPLAY 0.574468 (-6450 2350);
PAINT GREEN (-6450 2350);
DISPLAY INVISIBLE (-6450 2350);
FORCEPROP 1 LAST HDL_TAP TRUE
J 0
(-6125 2275);
DISPLAY 0.574468 (-6125 2275);
PAINT GREEN (-6125 2275);
DISPLAY INVISIBLE (-6125 2275);
FORCEPROP 1 LAST PATH I266
J 0
(-6452 2400);
DISPLAY 0.872340 (-6452 2400);
PAINT GREEN (-6452 2400);
DISPLAY INVISIBLE (-6452 2400);
FORCEADD TAP..6
(-6600 2550);
FORCEPROP 3 LASTPIN (-6550 2550) SIG_NAME P5E_CPU1_P1_RX_DN<3>
J 0
(-6540 2560);
DISPLAY 0.659574 (-6540 2560);
PAINT MONO (-6540 2560);
DISPLAY INVISIBLE (-6540 2560);
FORCEPROP 1 LASTPIN (-6550 2550) BN 3
J 0
(-6602 2558);
DISPLAY 0.489362 (-6602 2558);
PAINT MONO (-6602 2558);
FORCEPROP 2 LAST CDS_LIB standard
J 0
(-6600 2550);
DISPLAY INVISIBLE (-6600 2550);
FORCEPROP 1 LAST BODY_TYPE PLUMBING
J 0
(-6600 2500);
DISPLAY 0.574468 (-6600 2500);
PAINT GREEN (-6600 2500);
DISPLAY INVISIBLE (-6600 2500);
FORCEPROP 1 LAST HDL_TAP TRUE
J 0
(-6275 2425);
DISPLAY 0.574468 (-6275 2425);
PAINT GREEN (-6275 2425);
DISPLAY INVISIBLE (-6275 2425);
FORCEPROP 1 LAST PATH I267
J 0
(-6602 2550);
DISPLAY 0.872340 (-6602 2550);
PAINT GREEN (-6602 2550);
DISPLAY INVISIBLE (-6602 2550);
FORCEADD TAP..6
(-6600 2450);
FORCEPROP 3 LASTPIN (-6550 2450) SIG_NAME P5E_CPU1_P1_RX_DN<4>
J 0
(-6540 2460);
DISPLAY 0.659574 (-6540 2460);
PAINT MONO (-6540 2460);
DISPLAY INVISIBLE (-6540 2460);
FORCEPROP 1 LASTPIN (-6550 2450) BN 4
J 0
(-6602 2458);
DISPLAY 0.489362 (-6602 2458);
PAINT MONO (-6602 2458);
FORCEPROP 2 LAST CDS_LIB standard
J 0
(-6600 2450);
DISPLAY INVISIBLE (-6600 2450);
FORCEPROP 1 LAST BODY_TYPE PLUMBING
J 0
(-6600 2400);
DISPLAY 0.574468 (-6600 2400);
PAINT GREEN (-6600 2400);
DISPLAY INVISIBLE (-6600 2400);
FORCEPROP 1 LAST HDL_TAP TRUE
J 0
(-6275 2325);
DISPLAY 0.574468 (-6275 2325);
PAINT GREEN (-6275 2325);
DISPLAY INVISIBLE (-6275 2325);
FORCEPROP 1 LAST PATH I268
J 0
(-6602 2450);
DISPLAY 0.872340 (-6602 2450);
PAINT GREEN (-6602 2450);
DISPLAY INVISIBLE (-6602 2450);
FORCEADD TAP..6
(-6600 2350);
FORCEPROP 3 LASTPIN (-6550 2350) SIG_NAME P5E_CPU1_P1_RX_DN<5>
J 0
(-6540 2360);
DISPLAY 0.659574 (-6540 2360);
PAINT MONO (-6540 2360);
DISPLAY INVISIBLE (-6540 2360);
FORCEPROP 1 LASTPIN (-6550 2350) BN 5
J 0
(-6602 2358);
DISPLAY 0.489362 (-6602 2358);
PAINT MONO (-6602 2358);
FORCEPROP 2 LAST CDS_LIB standard
J 0
(-6600 2350);
DISPLAY INVISIBLE (-6600 2350);
FORCEPROP 1 LAST BODY_TYPE PLUMBING
J 0
(-6600 2300);
DISPLAY 0.574468 (-6600 2300);
PAINT GREEN (-6600 2300);
DISPLAY INVISIBLE (-6600 2300);
FORCEPROP 1 LAST HDL_TAP TRUE
J 0
(-6275 2225);
DISPLAY 0.574468 (-6275 2225);
PAINT GREEN (-6275 2225);
DISPLAY INVISIBLE (-6275 2225);
FORCEPROP 1 LAST PATH I269
J 0
(-6602 2350);
DISPLAY 0.872340 (-6602 2350);
PAINT GREEN (-6602 2350);
DISPLAY INVISIBLE (-6602 2350);
FORCEADD TAP..6
(-6600 2150);
FORCEPROP 3 LASTPIN (-6550 2150) SIG_NAME P5E_CPU1_P1_RX_DN<7>
J 0
(-6540 2160);
DISPLAY 0.659574 (-6540 2160);
PAINT MONO (-6540 2160);
DISPLAY INVISIBLE (-6540 2160);
FORCEPROP 1 LASTPIN (-6550 2150) BN 7
J 0
(-6602 2158);
DISPLAY 0.489362 (-6602 2158);
PAINT MONO (-6602 2158);
FORCEPROP 2 LAST CDS_LIB standard
J 0
(-6600 2150);
DISPLAY INVISIBLE (-6600 2150);
FORCEPROP 1 LAST BODY_TYPE PLUMBING
J 0
(-6600 2100);
DISPLAY 0.574468 (-6600 2100);
PAINT GREEN (-6600 2100);
DISPLAY INVISIBLE (-6600 2100);
FORCEPROP 1 LAST HDL_TAP TRUE
J 0
(-6275 2025);
DISPLAY 0.574468 (-6275 2025);
PAINT GREEN (-6275 2025);
DISPLAY INVISIBLE (-6275 2025);
FORCEPROP 1 LAST PATH I270
J 0
(-6602 2150);
DISPLAY 0.872340 (-6602 2150);
PAINT GREEN (-6602 2150);
DISPLAY INVISIBLE (-6602 2150);
FORCEADD TAP..6
(-6600 2250);
FORCEPROP 3 LASTPIN (-6550 2250) SIG_NAME P5E_CPU1_P1_RX_DN<6>
J 0
(-6540 2260);
DISPLAY 0.659574 (-6540 2260);
PAINT MONO (-6540 2260);
DISPLAY INVISIBLE (-6540 2260);
FORCEPROP 1 LASTPIN (-6550 2250) BN 6
J 0
(-6602 2258);
DISPLAY 0.489362 (-6602 2258);
PAINT MONO (-6602 2258);
FORCEPROP 2 LAST CDS_LIB standard
J 0
(-6600 2250);
DISPLAY INVISIBLE (-6600 2250);
FORCEPROP 1 LAST BODY_TYPE PLUMBING
J 0
(-6600 2200);
DISPLAY 0.574468 (-6600 2200);
PAINT GREEN (-6600 2200);
DISPLAY INVISIBLE (-6600 2200);
FORCEPROP 1 LAST HDL_TAP TRUE
J 0
(-6275 2125);
DISPLAY 0.574468 (-6275 2125);
PAINT GREEN (-6275 2125);
DISPLAY INVISIBLE (-6275 2125);
FORCEPROP 1 LAST PATH I271
J 0
(-6602 2250);
DISPLAY 0.872340 (-6602 2250);
PAINT GREEN (-6602 2250);
DISPLAY INVISIBLE (-6602 2250);
FORCEADD TAP..6
(-6600 2050);
FORCEPROP 3 LASTPIN (-6550 2050) SIG_NAME P5E_CPU1_P1_RX_DN<8>
J 0
(-6540 2060);
DISPLAY 0.659574 (-6540 2060);
PAINT MONO (-6540 2060);
DISPLAY INVISIBLE (-6540 2060);
FORCEPROP 1 LASTPIN (-6550 2050) BN 8
J 0
(-6602 2058);
DISPLAY 0.489362 (-6602 2058);
PAINT MONO (-6602 2058);
FORCEPROP 2 LAST CDS_LIB standard
J 0
(-6600 2050);
DISPLAY INVISIBLE (-6600 2050);
FORCEPROP 1 LAST BODY_TYPE PLUMBING
J 0
(-6600 2000);
DISPLAY 0.574468 (-6600 2000);
PAINT GREEN (-6600 2000);
DISPLAY INVISIBLE (-6600 2000);
FORCEPROP 1 LAST HDL_TAP TRUE
J 0
(-6275 1925);
DISPLAY 0.574468 (-6275 1925);
PAINT GREEN (-6275 1925);
DISPLAY INVISIBLE (-6275 1925);
FORCEPROP 1 LAST PATH I272
J 0
(-6602 2050);
DISPLAY 0.872340 (-6602 2050);
PAINT GREEN (-6602 2050);
DISPLAY INVISIBLE (-6602 2050);
FORCEADD OFFPAGE..1
(-7625 3125);
FORCEPROP 2 LAST $XR0 115 
J 0
(-7877 3125);
DISPLAY 0.638298 (-7877 3125);
PAINT MONO (-7877 3125);
FORCEPROP 2 LAST CDS_LIB standard
J 0
(-7625 3125);
DISPLAY INVISIBLE (-7625 3125);
FORCEPROP 1 LAST OFFPAGE TRUE
J 0
(-7300 3000);
DISPLAY 0.872340 (-7300 3000);
PAINT GREEN (-7300 3000);
DISPLAY INVISIBLE (-7300 3000);
FORCEPROP 1 LAST COMMENT_BODY TRUE
J 0
(-7500 3025);
DISPLAY 0.872340 (-7500 3025);
PAINT GREEN (-7500 3025);
DISPLAY INVISIBLE (-7500 3025);
FORCEPROP 2 LAST PATH I273
J 0
(-7575 3200);
DISPLAY 1.021277 (-7575 3200);
DISPLAY INVISIBLE (-7575 3200);
FORCEADD OFFPAGE..1
(-7625 3075);
FORCEPROP 2 LAST $XR0 115 
J 0
(-7877 3075);
DISPLAY 0.638298 (-7877 3075);
PAINT MONO (-7877 3075);
FORCEPROP 2 LAST CDS_LIB standard
J 0
(-7625 3075);
DISPLAY INVISIBLE (-7625 3075);
FORCEPROP 1 LAST OFFPAGE TRUE
J 0
(-7300 2950);
DISPLAY 0.872340 (-7300 2950);
PAINT GREEN (-7300 2950);
DISPLAY INVISIBLE (-7300 2950);
FORCEPROP 1 LAST COMMENT_BODY TRUE
J 0
(-7500 2975);
DISPLAY 0.872340 (-7500 2975);
PAINT GREEN (-7500 2975);
DISPLAY INVISIBLE (-7500 2975);
FORCEPROP 2 LAST PATH I274
J 0
(-7575 3150);
DISPLAY 1.021277 (-7575 3150);
DISPLAY INVISIBLE (-7575 3150);
FORCEADD TAP..6
(-6450 1800);
FORCEPROP 3 LASTPIN (-6400 1800) SIG_NAME P5E_CPU1_P1_RX_DP<11>
J 0
(-6390 1810);
DISPLAY 0.659574 (-6390 1810);
PAINT MONO (-6390 1810);
DISPLAY INVISIBLE (-6390 1810);
FORCEPROP 1 LASTPIN (-6400 1800) BN 11
J 0
(-6452 1808);
DISPLAY 0.489362 (-6452 1808);
PAINT MONO (-6452 1808);
FORCEPROP 2 LAST CDS_LIB standard
J 0
(-6450 1800);
DISPLAY INVISIBLE (-6450 1800);
FORCEPROP 1 LAST BODY_TYPE PLUMBING
J 0
(-6450 1750);
DISPLAY 0.574468 (-6450 1750);
PAINT GREEN (-6450 1750);
DISPLAY INVISIBLE (-6450 1750);
FORCEPROP 1 LAST HDL_TAP TRUE
J 0
(-6125 1675);
DISPLAY 0.574468 (-6125 1675);
PAINT GREEN (-6125 1675);
DISPLAY INVISIBLE (-6125 1675);
FORCEPROP 1 LAST PATH I275
J 0
(-6452 1800);
DISPLAY 0.872340 (-6452 1800);
PAINT GREEN (-6452 1800);
DISPLAY INVISIBLE (-6452 1800);
FORCEADD TAP..6
(-6450 1900);
FORCEPROP 3 LASTPIN (-6400 1900) SIG_NAME P5E_CPU1_P1_RX_DP<10>
J 0
(-6390 1910);
DISPLAY 0.659574 (-6390 1910);
PAINT MONO (-6390 1910);
DISPLAY INVISIBLE (-6390 1910);
FORCEPROP 1 LASTPIN (-6400 1900) BN 10
J 0
(-6452 1908);
DISPLAY 0.489362 (-6452 1908);
PAINT MONO (-6452 1908);
FORCEPROP 2 LAST CDS_LIB standard
J 0
(-6450 1900);
DISPLAY INVISIBLE (-6450 1900);
FORCEPROP 1 LAST BODY_TYPE PLUMBING
J 0
(-6450 1850);
DISPLAY 0.574468 (-6450 1850);
PAINT GREEN (-6450 1850);
DISPLAY INVISIBLE (-6450 1850);
FORCEPROP 1 LAST HDL_TAP TRUE
J 0
(-6125 1775);
DISPLAY 0.574468 (-6125 1775);
PAINT GREEN (-6125 1775);
DISPLAY INVISIBLE (-6125 1775);
FORCEPROP 1 LAST PATH I276
J 0
(-6452 1900);
DISPLAY 0.872340 (-6452 1900);
PAINT GREEN (-6452 1900);
DISPLAY INVISIBLE (-6452 1900);
FORCEADD TAP..6
(-6450 2000);
FORCEPROP 3 LASTPIN (-6400 2000) SIG_NAME P5E_CPU1_P1_RX_DP<9>
J 0
(-6390 2010);
DISPLAY 0.659574 (-6390 2010);
PAINT MONO (-6390 2010);
DISPLAY INVISIBLE (-6390 2010);
FORCEPROP 1 LASTPIN (-6400 2000) BN 9
J 0
(-6452 2008);
DISPLAY 0.489362 (-6452 2008);
PAINT MONO (-6452 2008);
FORCEPROP 2 LAST CDS_LIB standard
J 0
(-6450 2000);
DISPLAY INVISIBLE (-6450 2000);
FORCEPROP 1 LAST BODY_TYPE PLUMBING
J 0
(-6450 1950);
DISPLAY 0.574468 (-6450 1950);
PAINT GREEN (-6450 1950);
DISPLAY INVISIBLE (-6450 1950);
FORCEPROP 1 LAST HDL_TAP TRUE
J 0
(-6125 1875);
DISPLAY 0.574468 (-6125 1875);
PAINT GREEN (-6125 1875);
DISPLAY INVISIBLE (-6125 1875);
FORCEPROP 1 LAST PATH I277
J 0
(-6452 2000);
DISPLAY 0.872340 (-6452 2000);
PAINT GREEN (-6452 2000);
DISPLAY INVISIBLE (-6452 2000);
FORCEADD TAP..6
(-6450 1700);
FORCEPROP 3 LASTPIN (-6400 1700) SIG_NAME P5E_CPU1_P1_RX_DP<12>
J 0
(-6390 1710);
DISPLAY 0.659574 (-6390 1710);
PAINT MONO (-6390 1710);
DISPLAY INVISIBLE (-6390 1710);
FORCEPROP 1 LASTPIN (-6400 1700) BN 12
J 0
(-6452 1708);
DISPLAY 0.489362 (-6452 1708);
PAINT MONO (-6452 1708);
FORCEPROP 2 LAST CDS_LIB standard
J 0
(-6450 1700);
DISPLAY INVISIBLE (-6450 1700);
FORCEPROP 1 LAST BODY_TYPE PLUMBING
J 0
(-6450 1650);
DISPLAY 0.574468 (-6450 1650);
PAINT GREEN (-6450 1650);
DISPLAY INVISIBLE (-6450 1650);
FORCEPROP 1 LAST HDL_TAP TRUE
J 0
(-6125 1575);
DISPLAY 0.574468 (-6125 1575);
PAINT GREEN (-6125 1575);
DISPLAY INVISIBLE (-6125 1575);
FORCEPROP 1 LAST PATH I278
J 0
(-6452 1700);
DISPLAY 0.872340 (-6452 1700);
PAINT GREEN (-6452 1700);
DISPLAY INVISIBLE (-6452 1700);
FORCEADD TAP..6
(-6450 1600);
FORCEPROP 3 LASTPIN (-6400 1600) SIG_NAME P5E_CPU1_P1_RX_DP<13>
J 0
(-6390 1610);
DISPLAY 0.659574 (-6390 1610);
PAINT MONO (-6390 1610);
DISPLAY INVISIBLE (-6390 1610);
FORCEPROP 1 LASTPIN (-6400 1600) BN 13
J 0
(-6452 1608);
DISPLAY 0.489362 (-6452 1608);
PAINT MONO (-6452 1608);
FORCEPROP 2 LAST CDS_LIB standard
J 0
(-6450 1600);
DISPLAY INVISIBLE (-6450 1600);
FORCEPROP 1 LAST BODY_TYPE PLUMBING
J 0
(-6450 1550);
DISPLAY 0.574468 (-6450 1550);
PAINT GREEN (-6450 1550);
DISPLAY INVISIBLE (-6450 1550);
FORCEPROP 1 LAST HDL_TAP TRUE
J 0
(-6125 1475);
DISPLAY 0.574468 (-6125 1475);
PAINT GREEN (-6125 1475);
DISPLAY INVISIBLE (-6125 1475);
FORCEPROP 1 LAST PATH I279
J 0
(-6452 1600);
DISPLAY 0.872340 (-6452 1600);
PAINT GREEN (-6452 1600);
DISPLAY INVISIBLE (-6452 1600);
FORCEADD TAP..6
(-6600 1950);
FORCEPROP 3 LASTPIN (-6550 1950) SIG_NAME P5E_CPU1_P1_RX_DN<9>
J 0
(-6540 1960);
DISPLAY 0.659574 (-6540 1960);
PAINT MONO (-6540 1960);
DISPLAY INVISIBLE (-6540 1960);
FORCEPROP 1 LASTPIN (-6550 1950) BN 9
J 0
(-6602 1958);
DISPLAY 0.489362 (-6602 1958);
PAINT MONO (-6602 1958);
FORCEPROP 2 LAST CDS_LIB standard
J 0
(-6600 1950);
DISPLAY INVISIBLE (-6600 1950);
FORCEPROP 1 LAST BODY_TYPE PLUMBING
J 0
(-6600 1900);
DISPLAY 0.574468 (-6600 1900);
PAINT GREEN (-6600 1900);
DISPLAY INVISIBLE (-6600 1900);
FORCEPROP 1 LAST HDL_TAP TRUE
J 0
(-6275 1825);
DISPLAY 0.574468 (-6275 1825);
PAINT GREEN (-6275 1825);
DISPLAY INVISIBLE (-6275 1825);
FORCEPROP 1 LAST PATH I280
J 0
(-6602 1950);
DISPLAY 0.872340 (-6602 1950);
PAINT GREEN (-6602 1950);
DISPLAY INVISIBLE (-6602 1950);
FORCEADD TAP..6
(-6600 1850);
FORCEPROP 3 LASTPIN (-6550 1850) SIG_NAME P5E_CPU1_P1_RX_DN<10>
J 0
(-6540 1860);
DISPLAY 0.659574 (-6540 1860);
PAINT MONO (-6540 1860);
DISPLAY INVISIBLE (-6540 1860);
FORCEPROP 1 LASTPIN (-6550 1850) BN 10
J 0
(-6602 1858);
DISPLAY 0.489362 (-6602 1858);
PAINT MONO (-6602 1858);
FORCEPROP 2 LAST CDS_LIB standard
J 0
(-6600 1850);
DISPLAY INVISIBLE (-6600 1850);
FORCEPROP 1 LAST BODY_TYPE PLUMBING
J 0
(-6600 1800);
DISPLAY 0.574468 (-6600 1800);
PAINT GREEN (-6600 1800);
DISPLAY INVISIBLE (-6600 1800);
FORCEPROP 1 LAST HDL_TAP TRUE
J 0
(-6275 1725);
DISPLAY 0.574468 (-6275 1725);
PAINT GREEN (-6275 1725);
DISPLAY INVISIBLE (-6275 1725);
FORCEPROP 1 LAST PATH I281
J 0
(-6602 1850);
DISPLAY 0.872340 (-6602 1850);
PAINT GREEN (-6602 1850);
DISPLAY INVISIBLE (-6602 1850);
FORCEADD TAP..6
(-6600 1750);
FORCEPROP 3 LASTPIN (-6550 1750) SIG_NAME P5E_CPU1_P1_RX_DN<11>
J 0
(-6540 1760);
DISPLAY 0.659574 (-6540 1760);
PAINT MONO (-6540 1760);
DISPLAY INVISIBLE (-6540 1760);
FORCEPROP 1 LASTPIN (-6550 1750) BN 11
J 0
(-6602 1758);
DISPLAY 0.489362 (-6602 1758);
PAINT MONO (-6602 1758);
FORCEPROP 2 LAST CDS_LIB standard
J 0
(-6600 1750);
DISPLAY INVISIBLE (-6600 1750);
FORCEPROP 1 LAST BODY_TYPE PLUMBING
J 0
(-6600 1700);
DISPLAY 0.574468 (-6600 1700);
PAINT GREEN (-6600 1700);
DISPLAY INVISIBLE (-6600 1700);
FORCEPROP 1 LAST HDL_TAP TRUE
J 0
(-6275 1625);
DISPLAY 0.574468 (-6275 1625);
PAINT GREEN (-6275 1625);
DISPLAY INVISIBLE (-6275 1625);
FORCEPROP 1 LAST PATH I282
J 0
(-6602 1750);
DISPLAY 0.872340 (-6602 1750);
PAINT GREEN (-6602 1750);
DISPLAY INVISIBLE (-6602 1750);
FORCEADD TAP..6
(-6600 1650);
FORCEPROP 3 LASTPIN (-6550 1650) SIG_NAME P5E_CPU1_P1_RX_DN<12>
J 0
(-6540 1660);
DISPLAY 0.659574 (-6540 1660);
PAINT MONO (-6540 1660);
DISPLAY INVISIBLE (-6540 1660);
FORCEPROP 1 LASTPIN (-6550 1650) BN 12
J 0
(-6602 1658);
DISPLAY 0.489362 (-6602 1658);
PAINT MONO (-6602 1658);
FORCEPROP 2 LAST CDS_LIB standard
J 0
(-6600 1650);
DISPLAY INVISIBLE (-6600 1650);
FORCEPROP 1 LAST BODY_TYPE PLUMBING
J 0
(-6600 1600);
DISPLAY 0.574468 (-6600 1600);
PAINT GREEN (-6600 1600);
DISPLAY INVISIBLE (-6600 1600);
FORCEPROP 1 LAST HDL_TAP TRUE
J 0
(-6275 1525);
DISPLAY 0.574468 (-6275 1525);
PAINT GREEN (-6275 1525);
DISPLAY INVISIBLE (-6275 1525);
FORCEPROP 1 LAST PATH I283
J 0
(-6602 1650);
DISPLAY 0.872340 (-6602 1650);
PAINT GREEN (-6602 1650);
DISPLAY INVISIBLE (-6602 1650);
FORCEADD TAP..6
(-6600 1550);
FORCEPROP 3 LASTPIN (-6550 1550) SIG_NAME P5E_CPU1_P1_RX_DN<13>
J 0
(-6540 1560);
DISPLAY 0.659574 (-6540 1560);
PAINT MONO (-6540 1560);
DISPLAY INVISIBLE (-6540 1560);
FORCEPROP 1 LASTPIN (-6550 1550) BN 13
J 0
(-6602 1558);
DISPLAY 0.489362 (-6602 1558);
PAINT MONO (-6602 1558);
FORCEPROP 2 LAST CDS_LIB standard
J 0
(-6600 1550);
DISPLAY INVISIBLE (-6600 1550);
FORCEPROP 1 LAST BODY_TYPE PLUMBING
J 0
(-6600 1500);
DISPLAY 0.574468 (-6600 1500);
PAINT GREEN (-6600 1500);
DISPLAY INVISIBLE (-6600 1500);
FORCEPROP 1 LAST HDL_TAP TRUE
J 0
(-6275 1425);
DISPLAY 0.574468 (-6275 1425);
PAINT GREEN (-6275 1425);
DISPLAY INVISIBLE (-6275 1425);
FORCEPROP 1 LAST PATH I284
J 0
(-6602 1550);
DISPLAY 0.872340 (-6602 1550);
PAINT GREEN (-6602 1550);
DISPLAY INVISIBLE (-6602 1550);
FORCEADD TAP..6
(-6450 1500);
FORCEPROP 3 LASTPIN (-6400 1500) SIG_NAME P5E_CPU1_P1_RX_DP<14>
J 0
(-6390 1510);
DISPLAY 0.659574 (-6390 1510);
PAINT MONO (-6390 1510);
DISPLAY INVISIBLE (-6390 1510);
FORCEPROP 1 LASTPIN (-6400 1500) BN 14
J 0
(-6452 1508);
DISPLAY 0.489362 (-6452 1508);
PAINT MONO (-6452 1508);
FORCEPROP 2 LAST CDS_LIB standard
J 0
(-6450 1500);
DISPLAY INVISIBLE (-6450 1500);
FORCEPROP 1 LAST BODY_TYPE PLUMBING
J 0
(-6450 1450);
DISPLAY 0.574468 (-6450 1450);
PAINT GREEN (-6450 1450);
DISPLAY INVISIBLE (-6450 1450);
FORCEPROP 1 LAST HDL_TAP TRUE
J 0
(-6125 1375);
DISPLAY 0.574468 (-6125 1375);
PAINT GREEN (-6125 1375);
DISPLAY INVISIBLE (-6125 1375);
FORCEPROP 1 LAST PATH I285
J 0
(-6452 1500);
DISPLAY 0.872340 (-6452 1500);
PAINT GREEN (-6452 1500);
DISPLAY INVISIBLE (-6452 1500);
FORCEADD TAP..6
(-6450 1400);
FORCEPROP 3 LASTPIN (-6400 1400) SIG_NAME P5E_CPU1_P1_RX_DP<15>
J 0
(-6390 1410);
DISPLAY 0.659574 (-6390 1410);
PAINT MONO (-6390 1410);
DISPLAY INVISIBLE (-6390 1410);
FORCEPROP 1 LASTPIN (-6400 1400) BN 15
J 0
(-6452 1408);
DISPLAY 0.489362 (-6452 1408);
PAINT MONO (-6452 1408);
FORCEPROP 2 LAST CDS_LIB standard
J 0
(-6450 1400);
DISPLAY INVISIBLE (-6450 1400);
FORCEPROP 1 LAST BODY_TYPE PLUMBING
J 0
(-6450 1350);
DISPLAY 0.574468 (-6450 1350);
PAINT GREEN (-6450 1350);
DISPLAY INVISIBLE (-6450 1350);
FORCEPROP 1 LAST HDL_TAP TRUE
J 0
(-6125 1275);
DISPLAY 0.574468 (-6125 1275);
PAINT GREEN (-6125 1275);
DISPLAY INVISIBLE (-6125 1275);
FORCEPROP 1 LAST PATH I286
J 0
(-6452 1400);
DISPLAY 0.872340 (-6452 1400);
PAINT GREEN (-6452 1400);
DISPLAY INVISIBLE (-6452 1400);
FORCEADD TAP..6
(-6600 1350);
FORCEPROP 3 LASTPIN (-6550 1350) SIG_NAME P5E_CPU1_P1_RX_DN<15>
J 0
(-6540 1360);
DISPLAY 0.659574 (-6540 1360);
PAINT MONO (-6540 1360);
DISPLAY INVISIBLE (-6540 1360);
FORCEPROP 1 LASTPIN (-6550 1350) BN 15
J 0
(-6602 1358);
DISPLAY 0.489362 (-6602 1358);
PAINT MONO (-6602 1358);
FORCEPROP 2 LAST CDS_LIB standard
J 0
(-6600 1350);
DISPLAY INVISIBLE (-6600 1350);
FORCEPROP 1 LAST BODY_TYPE PLUMBING
J 0
(-6600 1300);
DISPLAY 0.574468 (-6600 1300);
PAINT GREEN (-6600 1300);
DISPLAY INVISIBLE (-6600 1300);
FORCEPROP 1 LAST HDL_TAP TRUE
J 0
(-6275 1225);
DISPLAY 0.574468 (-6275 1225);
PAINT GREEN (-6275 1225);
DISPLAY INVISIBLE (-6275 1225);
FORCEPROP 1 LAST PATH I287
J 0
(-6602 1350);
DISPLAY 0.872340 (-6602 1350);
PAINT GREEN (-6602 1350);
DISPLAY INVISIBLE (-6602 1350);
FORCEADD TAP..6
(-6600 1450);
FORCEPROP 3 LASTPIN (-6550 1450) SIG_NAME P5E_CPU1_P1_RX_DN<14>
J 0
(-6540 1460);
DISPLAY 0.659574 (-6540 1460);
PAINT MONO (-6540 1460);
DISPLAY INVISIBLE (-6540 1460);
FORCEPROP 1 LASTPIN (-6550 1450) BN 14
J 0
(-6602 1458);
DISPLAY 0.489362 (-6602 1458);
PAINT MONO (-6602 1458);
FORCEPROP 2 LAST CDS_LIB standard
J 0
(-6600 1450);
DISPLAY INVISIBLE (-6600 1450);
FORCEPROP 1 LAST BODY_TYPE PLUMBING
J 0
(-6600 1400);
DISPLAY 0.574468 (-6600 1400);
PAINT GREEN (-6600 1400);
DISPLAY INVISIBLE (-6600 1400);
FORCEPROP 1 LAST HDL_TAP TRUE
J 0
(-6275 1325);
DISPLAY 0.574468 (-6275 1325);
PAINT GREEN (-6275 1325);
DISPLAY INVISIBLE (-6275 1325);
FORCEPROP 1 LAST PATH I288
J 0
(-6602 1450);
DISPLAY 0.872340 (-6602 1450);
PAINT GREEN (-6602 1450);
DISPLAY INVISIBLE (-6602 1450);
FORCEADD OFFPAGE..2
(-1825 5775);
FORCEPROP 2 LAST $XR0 65 
J 0
(-1636 5775);
DISPLAY 0.638298 (-1636 5775);
PAINT MONO (-1636 5775);
FORCEPROP 2 LAST CDS_LIB standard
J 0
(-1825 5775);
DISPLAY INVISIBLE (-1825 5775);
FORCEPROP 1 LAST OFFPAGE TRUE
J 0
(-1500 5650);
DISPLAY 0.872340 (-1500 5650);
PAINT GREEN (-1500 5650);
DISPLAY INVISIBLE (-1500 5650);
FORCEPROP 1 LAST COMMENT_BODY TRUE
J 0
(-1870 5680);
DISPLAY 0.872340 (-1870 5680);
PAINT GREEN (-1870 5680);
DISPLAY INVISIBLE (-1870 5680);
FORCEPROP 2 LAST PATH I289
J 0
(-1650 5850);
DISPLAY 1.021277 (-1650 5850);
DISPLAY INVISIBLE (-1650 5850);
FORCEADD TAP..6
R 2
(-2950 5550);
FORCEPROP 3 LASTPIN (-3000 5550) SIG_NAME P5E_CPU1_P0_TX_DP<15>
J 0
(-2990 5560);
DISPLAY 0.659574 (-2990 5560);
PAINT MONO (-2990 5560);
DISPLAY INVISIBLE (-2990 5560);
FORCEPROP 1 LASTPIN (-3000 5550) BN 15
J 2
(-2948 5558);
DISPLAY 0.489362 (-2948 5558);
PAINT MONO (-2948 5558);
FORCEPROP 2 LAST CDS_LIB mstr_standard
J 0
(-2950 5550);
DISPLAY INVISIBLE (-2950 5550);
FORCEPROP 2 LAST BOM_COST IO_SLOT
J 0
(-3450 5650);
DISPLAY 0.829787 (-3450 5650);
DISPLAY INVISIBLE (-3450 5650);
FORCEPROP 1 LAST BODY_TYPE PLUMBING
J 2
(-2950 5500);
DISPLAY 0.702128 (-2950 5500);
PAINT GREEN (-2950 5500);
DISPLAY INVISIBLE (-2950 5500);
FORCEPROP 1 LAST HDL_TAP TRUE
J 2
(-3275 5425);
DISPLAY 0.702128 (-3275 5425);
PAINT GREEN (-3275 5425);
DISPLAY INVISIBLE (-3275 5425);
FORCEPROP 1 LAST PATH I291
J 2
(-2948 5550);
DISPLAY 0.872340 (-2948 5550);
PAINT GREEN (-2948 5550);
DISPLAY INVISIBLE (-2948 5550);
FORCEPROP 2 LAST ROOM RISER1
J 0
(-3450 5600);
DISPLAY 0.829787 (-3450 5600);
PAINT RED (-3450 5600);
DISPLAY INVISIBLE (-3450 5600);
FORCEADD TAP..6
R 2
(-2950 5350);
FORCEPROP 3 LASTPIN (-3000 5350) SIG_NAME P5E_CPU1_P0_TX_DP<13>
J 0
(-2990 5360);
DISPLAY 0.659574 (-2990 5360);
PAINT MONO (-2990 5360);
DISPLAY INVISIBLE (-2990 5360);
FORCEPROP 1 LASTPIN (-3000 5350) BN 13
J 2
(-2948 5358);
DISPLAY 0.489362 (-2948 5358);
PAINT MONO (-2948 5358);
FORCEPROP 2 LAST CDS_LIB standard
J 0
(-2950 5350);
DISPLAY INVISIBLE (-2950 5350);
FORCEPROP 2 LAST BOM_COST IO_SLOT
J 0
(-3450 5450);
DISPLAY 0.829787 (-3450 5450);
DISPLAY INVISIBLE (-3450 5450);
FORCEPROP 1 LAST BODY_TYPE PLUMBING
J 2
(-2950 5300);
DISPLAY 0.702128 (-2950 5300);
PAINT GREEN (-2950 5300);
DISPLAY INVISIBLE (-2950 5300);
FORCEPROP 1 LAST HDL_TAP TRUE
J 2
(-3275 5225);
DISPLAY 0.702128 (-3275 5225);
PAINT GREEN (-3275 5225);
DISPLAY INVISIBLE (-3275 5225);
FORCEPROP 1 LAST PATH I295
J 2
(-2948 5350);
DISPLAY 0.872340 (-2948 5350);
PAINT GREEN (-2948 5350);
DISPLAY INVISIBLE (-2948 5350);
FORCEPROP 2 LAST ROOM RISER1
J 0
(-3450 5400);
DISPLAY 0.829787 (-3450 5400);
PAINT RED (-3450 5400);
DISPLAY INVISIBLE (-3450 5400);
FORCEADD TAP..6
R 2
(-2950 5450);
FORCEPROP 3 LASTPIN (-3000 5450) SIG_NAME P5E_CPU1_P0_TX_DP<14>
J 0
(-2990 5460);
DISPLAY 0.659574 (-2990 5460);
PAINT MONO (-2990 5460);
DISPLAY INVISIBLE (-2990 5460);
FORCEPROP 1 LASTPIN (-3000 5450) BN 14
J 2
(-2948 5458);
DISPLAY 0.489362 (-2948 5458);
PAINT MONO (-2948 5458);
FORCEPROP 2 LAST CDS_LIB mstr_standard
J 0
(-2950 5450);
DISPLAY INVISIBLE (-2950 5450);
FORCEPROP 2 LAST BOM_COST IO_SLOT
J 0
(-3450 5550);
DISPLAY 0.829787 (-3450 5550);
DISPLAY INVISIBLE (-3450 5550);
FORCEPROP 1 LAST BODY_TYPE PLUMBING
J 2
(-2950 5400);
DISPLAY 0.702128 (-2950 5400);
PAINT GREEN (-2950 5400);
DISPLAY INVISIBLE (-2950 5400);
FORCEPROP 1 LAST HDL_TAP TRUE
J 2
(-3275 5325);
DISPLAY 0.702128 (-3275 5325);
PAINT GREEN (-3275 5325);
DISPLAY INVISIBLE (-3275 5325);
FORCEPROP 1 LAST PATH I296
J 2
(-2948 5450);
DISPLAY 0.872340 (-2948 5450);
PAINT GREEN (-2948 5450);
DISPLAY INVISIBLE (-2948 5450);
FORCEPROP 2 LAST ROOM RISER1
J 0
(-3450 5500);
DISPLAY 0.829787 (-3450 5500);
PAINT RED (-3450 5500);
DISPLAY INVISIBLE (-3450 5500);
FORCEADD TAP..6
R 2
(-2950 5150);
FORCEPROP 3 LASTPIN (-3000 5150) SIG_NAME P5E_CPU1_P0_TX_DP<11>
J 0
(-2990 5160);
DISPLAY 0.659574 (-2990 5160);
PAINT MONO (-2990 5160);
DISPLAY INVISIBLE (-2990 5160);
FORCEPROP 1 LASTPIN (-3000 5150) BN 11
J 2
(-2948 5158);
DISPLAY 0.489362 (-2948 5158);
PAINT MONO (-2948 5158);
FORCEPROP 2 LAST CDS_LIB standard
J 0
(-2950 5150);
DISPLAY INVISIBLE (-2950 5150);
FORCEPROP 2 LAST BOM_COST IO_SLOT
J 0
(-3450 5250);
DISPLAY 0.829787 (-3450 5250);
DISPLAY INVISIBLE (-3450 5250);
FORCEPROP 1 LAST BODY_TYPE PLUMBING
J 2
(-2950 5100);
DISPLAY 0.702128 (-2950 5100);
PAINT GREEN (-2950 5100);
DISPLAY INVISIBLE (-2950 5100);
FORCEPROP 1 LAST HDL_TAP TRUE
J 2
(-3275 5025);
DISPLAY 0.702128 (-3275 5025);
PAINT GREEN (-3275 5025);
DISPLAY INVISIBLE (-3275 5025);
FORCEPROP 1 LAST PATH I299
J 2
(-2948 5150);
DISPLAY 0.872340 (-2948 5150);
PAINT GREEN (-2948 5150);
DISPLAY INVISIBLE (-2948 5150);
FORCEPROP 2 LAST ROOM RISER1
J 0
(-3450 5200);
DISPLAY 0.829787 (-3450 5200);
PAINT RED (-3450 5200);
DISPLAY INVISIBLE (-3450 5200);
FORCEADD TAP..6
R 2
(-2950 5250);
FORCEPROP 3 LASTPIN (-3000 5250) SIG_NAME P5E_CPU1_P0_TX_DP<12>
J 0
(-2990 5260);
DISPLAY 0.659574 (-2990 5260);
PAINT MONO (-2990 5260);
DISPLAY INVISIBLE (-2990 5260);
FORCEPROP 1 LASTPIN (-3000 5250) BN 12
J 2
(-2948 5258);
DISPLAY 0.489362 (-2948 5258);
PAINT MONO (-2948 5258);
FORCEPROP 2 LAST CDS_LIB standard
J 0
(-2950 5250);
DISPLAY INVISIBLE (-2950 5250);
FORCEPROP 2 LAST BOM_COST IO_SLOT
J 0
(-3450 5350);
DISPLAY 0.829787 (-3450 5350);
DISPLAY INVISIBLE (-3450 5350);
FORCEPROP 1 LAST BODY_TYPE PLUMBING
J 2
(-2950 5200);
DISPLAY 0.702128 (-2950 5200);
PAINT GREEN (-2950 5200);
DISPLAY INVISIBLE (-2950 5200);
FORCEPROP 1 LAST HDL_TAP TRUE
J 2
(-3275 5125);
DISPLAY 0.702128 (-3275 5125);
PAINT GREEN (-3275 5125);
DISPLAY INVISIBLE (-3275 5125);
FORCEPROP 1 LAST PATH I300
J 2
(-2948 5250);
DISPLAY 0.872340 (-2948 5250);
PAINT GREEN (-2948 5250);
DISPLAY INVISIBLE (-2948 5250);
FORCEPROP 2 LAST ROOM RISER1
J 0
(-3450 5300);
DISPLAY 0.829787 (-3450 5300);
PAINT RED (-3450 5300);
DISPLAY INVISIBLE (-3450 5300);
FORCEADD TAP..6
R 2
(-2950 5050);
FORCEPROP 3 LASTPIN (-3000 5050) SIG_NAME P5E_CPU1_P0_TX_DP<10>
J 0
(-2990 5060);
DISPLAY 0.659574 (-2990 5060);
PAINT MONO (-2990 5060);
DISPLAY INVISIBLE (-2990 5060);
FORCEPROP 1 LASTPIN (-3000 5050) BN 10
J 2
(-2948 5058);
DISPLAY 0.489362 (-2948 5058);
PAINT MONO (-2948 5058);
FORCEPROP 2 LAST CDS_LIB standard
J 0
(-2950 5050);
DISPLAY INVISIBLE (-2950 5050);
FORCEPROP 2 LAST BOM_COST IO_SLOT
J 0
(-3450 5150);
DISPLAY 0.829787 (-3450 5150);
DISPLAY INVISIBLE (-3450 5150);
FORCEPROP 1 LAST BODY_TYPE PLUMBING
J 2
(-2950 5000);
DISPLAY 0.702128 (-2950 5000);
PAINT GREEN (-2950 5000);
DISPLAY INVISIBLE (-2950 5000);
FORCEPROP 1 LAST HDL_TAP TRUE
J 2
(-3275 4925);
DISPLAY 0.702128 (-3275 4925);
PAINT GREEN (-3275 4925);
DISPLAY INVISIBLE (-3275 4925);
FORCEPROP 1 LAST PATH I301
J 2
(-2948 5050);
DISPLAY 0.872340 (-2948 5050);
PAINT GREEN (-2948 5050);
DISPLAY INVISIBLE (-2948 5050);
FORCEPROP 2 LAST ROOM RISER1
J 0
(-3450 5100);
DISPLAY 0.829787 (-3450 5100);
PAINT RED (-3450 5100);
DISPLAY INVISIBLE (-3450 5100);
FORCEADD TAP..6
R 2
(-2950 4950);
FORCEPROP 3 LASTPIN (-3000 4950) SIG_NAME P5E_CPU1_P0_TX_DP<9>
J 0
(-2990 4960);
DISPLAY 0.659574 (-2990 4960);
PAINT MONO (-2990 4960);
DISPLAY INVISIBLE (-2990 4960);
FORCEPROP 1 LASTPIN (-3000 4950) BN 9
J 2
(-2948 4958);
DISPLAY 0.489362 (-2948 4958);
PAINT MONO (-2948 4958);
FORCEPROP 2 LAST CDS_LIB standard
J 0
(-2950 4950);
DISPLAY INVISIBLE (-2950 4950);
FORCEPROP 2 LAST BOM_COST IO_SLOT
J 0
(-3450 5050);
DISPLAY 0.829787 (-3450 5050);
DISPLAY INVISIBLE (-3450 5050);
FORCEPROP 1 LAST BODY_TYPE PLUMBING
J 2
(-2950 4900);
DISPLAY 0.702128 (-2950 4900);
PAINT GREEN (-2950 4900);
DISPLAY INVISIBLE (-2950 4900);
FORCEPROP 1 LAST HDL_TAP TRUE
J 2
(-3275 4825);
DISPLAY 0.702128 (-3275 4825);
PAINT GREEN (-3275 4825);
DISPLAY INVISIBLE (-3275 4825);
FORCEPROP 1 LAST PATH I305
J 2
(-2948 4950);
DISPLAY 0.872340 (-2948 4950);
PAINT GREEN (-2948 4950);
DISPLAY INVISIBLE (-2948 4950);
FORCEPROP 2 LAST ROOM RISER1
J 0
(-3450 5000);
DISPLAY 0.829787 (-3450 5000);
PAINT RED (-3450 5000);
DISPLAY INVISIBLE (-3450 5000);
FORCEADD TAP..6
R 2
(-2950 4850);
FORCEPROP 3 LASTPIN (-3000 4850) SIG_NAME P5E_CPU1_P0_TX_DP<8>
J 0
(-2990 4860);
DISPLAY 0.659574 (-2990 4860);
PAINT MONO (-2990 4860);
DISPLAY INVISIBLE (-2990 4860);
FORCEPROP 1 LASTPIN (-3000 4850) BN 8
J 2
(-2948 4858);
DISPLAY 0.489362 (-2948 4858);
PAINT MONO (-2948 4858);
FORCEPROP 2 LAST CDS_LIB standard
J 0
(-2950 4850);
DISPLAY INVISIBLE (-2950 4850);
FORCEPROP 2 LAST BOM_COST IO_SLOT
J 0
(-3450 4950);
DISPLAY 0.829787 (-3450 4950);
DISPLAY INVISIBLE (-3450 4950);
FORCEPROP 1 LAST BODY_TYPE PLUMBING
J 2
(-2950 4800);
DISPLAY 0.702128 (-2950 4800);
PAINT GREEN (-2950 4800);
DISPLAY INVISIBLE (-2950 4800);
FORCEPROP 1 LAST HDL_TAP TRUE
J 2
(-3275 4725);
DISPLAY 0.702128 (-3275 4725);
PAINT GREEN (-3275 4725);
DISPLAY INVISIBLE (-3275 4725);
FORCEPROP 1 LAST PATH I306
J 2
(-2948 4850);
DISPLAY 0.872340 (-2948 4850);
PAINT GREEN (-2948 4850);
DISPLAY INVISIBLE (-2948 4850);
FORCEPROP 2 LAST ROOM RISER1
J 0
(-3450 4900);
DISPLAY 0.829787 (-3450 4900);
PAINT RED (-3450 4900);
DISPLAY INVISIBLE (-3450 4900);
FORCEADD TAP..6
R 2
(-2950 4750);
FORCEPROP 3 LASTPIN (-3000 4750) SIG_NAME P5E_CPU1_P0_TX_DP<7>
J 0
(-2990 4760);
DISPLAY 0.659574 (-2990 4760);
PAINT MONO (-2990 4760);
DISPLAY INVISIBLE (-2990 4760);
FORCEPROP 1 LASTPIN (-3000 4750) BN 7
J 2
(-2948 4758);
DISPLAY 0.489362 (-2948 4758);
PAINT MONO (-2948 4758);
FORCEPROP 2 LAST CDS_LIB standard
J 0
(-2950 4750);
DISPLAY INVISIBLE (-2950 4750);
FORCEPROP 2 LAST BOM_COST IO_SLOT
J 0
(-3450 4850);
DISPLAY 0.829787 (-3450 4850);
DISPLAY INVISIBLE (-3450 4850);
FORCEPROP 1 LAST BODY_TYPE PLUMBING
J 2
(-2950 4700);
DISPLAY 0.702128 (-2950 4700);
PAINT GREEN (-2950 4700);
DISPLAY INVISIBLE (-2950 4700);
FORCEPROP 1 LAST HDL_TAP TRUE
J 2
(-3275 4625);
DISPLAY 0.702128 (-3275 4625);
PAINT GREEN (-3275 4625);
DISPLAY INVISIBLE (-3275 4625);
FORCEPROP 1 LAST PATH I307
J 2
(-2948 4750);
DISPLAY 0.872340 (-2948 4750);
PAINT GREEN (-2948 4750);
DISPLAY INVISIBLE (-2948 4750);
FORCEPROP 2 LAST ROOM RISER1
J 0
(-3450 4800);
DISPLAY 0.829787 (-3450 4800);
PAINT RED (-3450 4800);
DISPLAY INVISIBLE (-3450 4800);
FORCEADD TAP..6
R 2
(-2950 4650);
FORCEPROP 3 LASTPIN (-3000 4650) SIG_NAME P5E_CPU1_P0_TX_DP<6>
J 0
(-2990 4660);
DISPLAY 0.659574 (-2990 4660);
PAINT MONO (-2990 4660);
DISPLAY INVISIBLE (-2990 4660);
FORCEPROP 1 LASTPIN (-3000 4650) BN 6
J 2
(-2948 4658);
DISPLAY 0.489362 (-2948 4658);
PAINT MONO (-2948 4658);
FORCEPROP 2 LAST CDS_LIB standard
J 0
(-2950 4650);
DISPLAY INVISIBLE (-2950 4650);
FORCEPROP 2 LAST BOM_COST IO_SLOT
J 0
(-3450 4750);
DISPLAY 0.829787 (-3450 4750);
DISPLAY INVISIBLE (-3450 4750);
FORCEPROP 1 LAST BODY_TYPE PLUMBING
J 2
(-2950 4600);
DISPLAY 0.702128 (-2950 4600);
PAINT GREEN (-2950 4600);
DISPLAY INVISIBLE (-2950 4600);
FORCEPROP 1 LAST HDL_TAP TRUE
J 2
(-3275 4525);
DISPLAY 0.702128 (-3275 4525);
PAINT GREEN (-3275 4525);
DISPLAY INVISIBLE (-3275 4525);
FORCEPROP 1 LAST PATH I311
J 2
(-2948 4650);
DISPLAY 0.872340 (-2948 4650);
PAINT GREEN (-2948 4650);
DISPLAY INVISIBLE (-2948 4650);
FORCEPROP 2 LAST ROOM RISER1
J 0
(-3450 4700);
DISPLAY 0.829787 (-3450 4700);
PAINT RED (-3450 4700);
DISPLAY INVISIBLE (-3450 4700);
FORCEADD TAP..6
R 2
(-2950 4550);
FORCEPROP 3 LASTPIN (-3000 4550) SIG_NAME P5E_CPU1_P0_TX_DP<5>
J 0
(-2990 4560);
DISPLAY 0.659574 (-2990 4560);
PAINT MONO (-2990 4560);
DISPLAY INVISIBLE (-2990 4560);
FORCEPROP 1 LASTPIN (-3000 4550) BN 5
J 2
(-2948 4558);
DISPLAY 0.489362 (-2948 4558);
PAINT MONO (-2948 4558);
FORCEPROP 2 LAST CDS_LIB standard
J 0
(-2950 4550);
DISPLAY INVISIBLE (-2950 4550);
FORCEPROP 2 LAST BOM_COST IO_SLOT
J 0
(-3450 4650);
DISPLAY 0.829787 (-3450 4650);
DISPLAY INVISIBLE (-3450 4650);
FORCEPROP 1 LAST BODY_TYPE PLUMBING
J 2
(-2950 4500);
DISPLAY 0.702128 (-2950 4500);
PAINT GREEN (-2950 4500);
DISPLAY INVISIBLE (-2950 4500);
FORCEPROP 1 LAST HDL_TAP TRUE
J 2
(-3275 4425);
DISPLAY 0.702128 (-3275 4425);
PAINT GREEN (-3275 4425);
DISPLAY INVISIBLE (-3275 4425);
FORCEPROP 1 LAST PATH I312
J 2
(-2948 4550);
DISPLAY 0.872340 (-2948 4550);
PAINT GREEN (-2948 4550);
DISPLAY INVISIBLE (-2948 4550);
FORCEPROP 2 LAST ROOM RISER1
J 0
(-3450 4600);
DISPLAY 0.829787 (-3450 4600);
PAINT RED (-3450 4600);
DISPLAY INVISIBLE (-3450 4600);
FORCEADD TAP..6
R 2
(-2950 4450);
FORCEPROP 3 LASTPIN (-3000 4450) SIG_NAME P5E_CPU1_P0_TX_DP<4>
J 0
(-2990 4460);
DISPLAY 0.659574 (-2990 4460);
PAINT MONO (-2990 4460);
DISPLAY INVISIBLE (-2990 4460);
FORCEPROP 1 LASTPIN (-3000 4450) BN 4
J 2
(-2948 4458);
DISPLAY 0.489362 (-2948 4458);
PAINT MONO (-2948 4458);
FORCEPROP 2 LAST CDS_LIB standard
J 0
(-2950 4450);
DISPLAY INVISIBLE (-2950 4450);
FORCEPROP 2 LAST BOM_COST IO_SLOT
J 0
(-3450 4550);
DISPLAY 0.829787 (-3450 4550);
DISPLAY INVISIBLE (-3450 4550);
FORCEPROP 1 LAST BODY_TYPE PLUMBING
J 2
(-2950 4400);
DISPLAY 0.702128 (-2950 4400);
PAINT GREEN (-2950 4400);
DISPLAY INVISIBLE (-2950 4400);
FORCEPROP 1 LAST HDL_TAP TRUE
J 2
(-3275 4325);
DISPLAY 0.702128 (-3275 4325);
PAINT GREEN (-3275 4325);
DISPLAY INVISIBLE (-3275 4325);
FORCEPROP 1 LAST PATH I315
J 2
(-2948 4450);
DISPLAY 0.872340 (-2948 4450);
PAINT GREEN (-2948 4450);
DISPLAY INVISIBLE (-2948 4450);
FORCEPROP 2 LAST ROOM RISER1
J 0
(-3450 4500);
DISPLAY 0.829787 (-3450 4500);
PAINT RED (-3450 4500);
DISPLAY INVISIBLE (-3450 4500);
FORCEADD TAP..6
R 2
(-2950 4350);
FORCEPROP 3 LASTPIN (-3000 4350) SIG_NAME P5E_CPU1_P0_TX_DP<3>
J 0
(-2990 4360);
DISPLAY 0.659574 (-2990 4360);
PAINT MONO (-2990 4360);
DISPLAY INVISIBLE (-2990 4360);
FORCEPROP 1 LASTPIN (-3000 4350) BN 3
J 2
(-2948 4358);
DISPLAY 0.489362 (-2948 4358);
PAINT MONO (-2948 4358);
FORCEPROP 2 LAST CDS_LIB standard
J 0
(-2950 4350);
DISPLAY INVISIBLE (-2950 4350);
FORCEPROP 2 LAST BOM_COST IO_SLOT
J 0
(-3450 4450);
DISPLAY 0.829787 (-3450 4450);
DISPLAY INVISIBLE (-3450 4450);
FORCEPROP 1 LAST BODY_TYPE PLUMBING
J 2
(-2950 4300);
DISPLAY 0.702128 (-2950 4300);
PAINT GREEN (-2950 4300);
DISPLAY INVISIBLE (-2950 4300);
FORCEPROP 1 LAST HDL_TAP TRUE
J 2
(-3275 4225);
DISPLAY 0.702128 (-3275 4225);
PAINT GREEN (-3275 4225);
DISPLAY INVISIBLE (-3275 4225);
FORCEPROP 1 LAST PATH I316
J 2
(-2948 4350);
DISPLAY 0.872340 (-2948 4350);
PAINT GREEN (-2948 4350);
DISPLAY INVISIBLE (-2948 4350);
FORCEPROP 2 LAST ROOM RISER1
J 0
(-3450 4400);
DISPLAY 0.829787 (-3450 4400);
PAINT RED (-3450 4400);
DISPLAY INVISIBLE (-3450 4400);
FORCEADD TAP..6
R 2
(-2950 4250);
FORCEPROP 3 LASTPIN (-3000 4250) SIG_NAME P5E_CPU1_P0_TX_DP<2>
J 0
(-2990 4260);
DISPLAY 0.659574 (-2990 4260);
PAINT MONO (-2990 4260);
DISPLAY INVISIBLE (-2990 4260);
FORCEPROP 1 LASTPIN (-3000 4250) BN 2
J 2
(-2948 4258);
DISPLAY 0.489362 (-2948 4258);
PAINT MONO (-2948 4258);
FORCEPROP 2 LAST CDS_LIB standard
J 0
(-2950 4250);
DISPLAY INVISIBLE (-2950 4250);
FORCEPROP 2 LAST BOM_COST IO_SLOT
J 0
(-3450 4350);
DISPLAY 0.829787 (-3450 4350);
DISPLAY INVISIBLE (-3450 4350);
FORCEPROP 1 LAST BODY_TYPE PLUMBING
J 2
(-2950 4200);
DISPLAY 0.702128 (-2950 4200);
PAINT GREEN (-2950 4200);
DISPLAY INVISIBLE (-2950 4200);
FORCEPROP 1 LAST HDL_TAP TRUE
J 2
(-3275 4125);
DISPLAY 0.702128 (-3275 4125);
PAINT GREEN (-3275 4125);
DISPLAY INVISIBLE (-3275 4125);
FORCEPROP 1 LAST PATH I317
J 2
(-2948 4250);
DISPLAY 0.872340 (-2948 4250);
PAINT GREEN (-2948 4250);
DISPLAY INVISIBLE (-2948 4250);
FORCEPROP 2 LAST ROOM RISER1
J 0
(-3450 4300);
DISPLAY 0.829787 (-3450 4300);
PAINT RED (-3450 4300);
DISPLAY INVISIBLE (-3450 4300);
FORCEADD TAP..6
R 2
(-2950 4150);
FORCEPROP 3 LASTPIN (-3000 4150) SIG_NAME P5E_CPU1_P0_TX_DP<1>
J 0
(-2990 4160);
DISPLAY 0.659574 (-2990 4160);
PAINT MONO (-2990 4160);
DISPLAY INVISIBLE (-2990 4160);
FORCEPROP 1 LASTPIN (-3000 4150) BN 1
J 2
(-2948 4158);
DISPLAY 0.489362 (-2948 4158);
PAINT MONO (-2948 4158);
FORCEPROP 2 LAST CDS_LIB standard
J 0
(-2950 4150);
DISPLAY INVISIBLE (-2950 4150);
FORCEPROP 2 LAST BOM_COST IO_SLOT
J 0
(-3450 4250);
DISPLAY 0.829787 (-3450 4250);
DISPLAY INVISIBLE (-3450 4250);
FORCEPROP 1 LAST BODY_TYPE PLUMBING
J 2
(-2950 4100);
DISPLAY 0.702128 (-2950 4100);
PAINT GREEN (-2950 4100);
DISPLAY INVISIBLE (-2950 4100);
FORCEPROP 1 LAST HDL_TAP TRUE
J 2
(-3275 4025);
DISPLAY 0.702128 (-3275 4025);
PAINT GREEN (-3275 4025);
DISPLAY INVISIBLE (-3275 4025);
FORCEPROP 1 LAST PATH I321
J 2
(-2948 4150);
DISPLAY 0.872340 (-2948 4150);
PAINT GREEN (-2948 4150);
DISPLAY INVISIBLE (-2948 4150);
FORCEPROP 2 LAST ROOM RISER1
J 0
(-3450 4200);
DISPLAY 0.829787 (-3450 4200);
PAINT RED (-3450 4200);
DISPLAY INVISIBLE (-3450 4200);
FORCEADD TAP..6
R 2
(-2950 4050);
FORCEPROP 3 LASTPIN (-3000 4050) SIG_NAME P5E_CPU1_P0_TX_DP<0>
J 0
(-2990 4060);
DISPLAY 0.659574 (-2990 4060);
PAINT MONO (-2990 4060);
DISPLAY INVISIBLE (-2990 4060);
FORCEPROP 1 LASTPIN (-3000 4050) BN 0
J 2
(-2948 4058);
DISPLAY 0.489362 (-2948 4058);
PAINT MONO (-2948 4058);
FORCEPROP 2 LAST CDS_LIB standard
J 0
(-2950 4050);
DISPLAY INVISIBLE (-2950 4050);
FORCEPROP 2 LAST BOM_COST IO_SLOT
J 0
(-3450 4150);
DISPLAY 0.829787 (-3450 4150);
DISPLAY INVISIBLE (-3450 4150);
FORCEPROP 1 LAST BODY_TYPE PLUMBING
J 2
(-2950 4000);
DISPLAY 0.702128 (-2950 4000);
PAINT GREEN (-2950 4000);
DISPLAY INVISIBLE (-2950 4000);
FORCEPROP 1 LAST HDL_TAP TRUE
J 2
(-3275 3925);
DISPLAY 0.702128 (-3275 3925);
PAINT GREEN (-3275 3925);
DISPLAY INVISIBLE (-3275 3925);
FORCEPROP 1 LAST PATH I322
J 2
(-2948 4050);
DISPLAY 0.872340 (-2948 4050);
PAINT GREEN (-2948 4050);
DISPLAY INVISIBLE (-2948 4050);
FORCEPROP 2 LAST ROOM RISER1
J 0
(-3450 4100);
DISPLAY 0.829787 (-3450 4100);
PAINT RED (-3450 4100);
DISPLAY INVISIBLE (-3450 4100);
FORCEADD TAP..6
(-6600 5500);
FORCEPROP 3 LASTPIN (-6550 5500) SIG_NAME P5E_CPU1_P0_RX_DP<15>
J 0
(-6540 5510);
DISPLAY 0.659574 (-6540 5510);
PAINT MONO (-6540 5510);
DISPLAY INVISIBLE (-6540 5510);
FORCEPROP 1 LASTPIN (-6550 5500) BN 15
J 0
(-6602 5508);
DISPLAY 0.489362 (-6602 5508);
PAINT MONO (-6602 5508);
FORCEPROP 2 LAST CDS_LIB mstr_standard
J 0
(-6600 5500);
DISPLAY INVISIBLE (-6600 5500);
FORCEPROP 1 LAST BODY_TYPE PLUMBING
J 0
(-6600 5450);
DISPLAY 0.574468 (-6600 5450);
PAINT GREEN (-6600 5450);
DISPLAY INVISIBLE (-6600 5450);
FORCEPROP 1 LAST HDL_TAP TRUE
J 0
(-6275 5375);
DISPLAY 0.574468 (-6275 5375);
PAINT GREEN (-6275 5375);
DISPLAY INVISIBLE (-6275 5375);
FORCEPROP 1 LAST PATH I323
J 0
(-6602 5500);
DISPLAY 0.872340 (-6602 5500);
PAINT GREEN (-6602 5500);
DISPLAY INVISIBLE (-6602 5500);
FORCEADD TAP..6
(-6600 5400);
FORCEPROP 3 LASTPIN (-6550 5400) SIG_NAME P5E_CPU1_P0_RX_DP<14>
J 0
(-6540 5410);
DISPLAY 0.659574 (-6540 5410);
PAINT MONO (-6540 5410);
DISPLAY INVISIBLE (-6540 5410);
FORCEPROP 1 LASTPIN (-6550 5400) BN 14
J 0
(-6602 5408);
DISPLAY 0.489362 (-6602 5408);
PAINT MONO (-6602 5408);
FORCEPROP 2 LAST CDS_LIB mstr_standard
J 0
(-6600 5400);
DISPLAY INVISIBLE (-6600 5400);
FORCEPROP 1 LAST BODY_TYPE PLUMBING
J 0
(-6600 5350);
DISPLAY 0.574468 (-6600 5350);
PAINT GREEN (-6600 5350);
DISPLAY INVISIBLE (-6600 5350);
FORCEPROP 1 LAST HDL_TAP TRUE
J 0
(-6275 5275);
DISPLAY 0.574468 (-6275 5275);
PAINT GREEN (-6275 5275);
DISPLAY INVISIBLE (-6275 5275);
FORCEPROP 1 LAST PATH I324
J 0
(-6602 5400);
DISPLAY 0.872340 (-6602 5400);
PAINT GREEN (-6602 5400);
DISPLAY INVISIBLE (-6602 5400);
FORCEADD TAP..6
(-6600 5300);
FORCEPROP 3 LASTPIN (-6550 5300) SIG_NAME P5E_CPU1_P0_RX_DP<13>
J 0
(-6540 5310);
DISPLAY 0.659574 (-6540 5310);
PAINT MONO (-6540 5310);
DISPLAY INVISIBLE (-6540 5310);
FORCEPROP 1 LASTPIN (-6550 5300) BN 13
J 0
(-6602 5308);
DISPLAY 0.489362 (-6602 5308);
PAINT MONO (-6602 5308);
FORCEPROP 2 LAST CDS_LIB standard
J 0
(-6600 5300);
DISPLAY INVISIBLE (-6600 5300);
FORCEPROP 1 LAST BODY_TYPE PLUMBING
J 0
(-6600 5250);
DISPLAY 0.574468 (-6600 5250);
PAINT GREEN (-6600 5250);
DISPLAY INVISIBLE (-6600 5250);
FORCEPROP 1 LAST HDL_TAP TRUE
J 0
(-6275 5175);
DISPLAY 0.574468 (-6275 5175);
PAINT GREEN (-6275 5175);
DISPLAY INVISIBLE (-6275 5175);
FORCEPROP 1 LAST PATH I325
J 0
(-6602 5300);
DISPLAY 0.872340 (-6602 5300);
PAINT GREEN (-6602 5300);
DISPLAY INVISIBLE (-6602 5300);
FORCEADD TAP..6
(-6600 5200);
FORCEPROP 3 LASTPIN (-6550 5200) SIG_NAME P5E_CPU1_P0_RX_DP<12>
J 0
(-6540 5210);
DISPLAY 0.659574 (-6540 5210);
PAINT MONO (-6540 5210);
DISPLAY INVISIBLE (-6540 5210);
FORCEPROP 1 LASTPIN (-6550 5200) BN 12
J 0
(-6602 5208);
DISPLAY 0.489362 (-6602 5208);
PAINT MONO (-6602 5208);
FORCEPROP 2 LAST CDS_LIB standard
J 0
(-6600 5200);
DISPLAY INVISIBLE (-6600 5200);
FORCEPROP 1 LAST BODY_TYPE PLUMBING
J 0
(-6600 5150);
DISPLAY 0.574468 (-6600 5150);
PAINT GREEN (-6600 5150);
DISPLAY INVISIBLE (-6600 5150);
FORCEPROP 1 LAST HDL_TAP TRUE
J 0
(-6275 5075);
DISPLAY 0.574468 (-6275 5075);
PAINT GREEN (-6275 5075);
DISPLAY INVISIBLE (-6275 5075);
FORCEPROP 1 LAST PATH I326
J 0
(-6602 5200);
DISPLAY 0.872340 (-6602 5200);
PAINT GREEN (-6602 5200);
DISPLAY INVISIBLE (-6602 5200);
FORCEADD TAP..6
(-6600 5100);
FORCEPROP 3 LASTPIN (-6550 5100) SIG_NAME P5E_CPU1_P0_RX_DP<11>
J 0
(-6540 5110);
DISPLAY 0.659574 (-6540 5110);
PAINT MONO (-6540 5110);
DISPLAY INVISIBLE (-6540 5110);
FORCEPROP 1 LASTPIN (-6550 5100) BN 11
J 0
(-6602 5108);
DISPLAY 0.489362 (-6602 5108);
PAINT MONO (-6602 5108);
FORCEPROP 2 LAST CDS_LIB standard
J 0
(-6600 5100);
DISPLAY INVISIBLE (-6600 5100);
FORCEPROP 1 LAST BODY_TYPE PLUMBING
J 0
(-6600 5050);
DISPLAY 0.574468 (-6600 5050);
PAINT GREEN (-6600 5050);
DISPLAY INVISIBLE (-6600 5050);
FORCEPROP 1 LAST HDL_TAP TRUE
J 0
(-6275 4975);
DISPLAY 0.574468 (-6275 4975);
PAINT GREEN (-6275 4975);
DISPLAY INVISIBLE (-6275 4975);
FORCEPROP 1 LAST PATH I327
J 0
(-6602 5100);
DISPLAY 0.872340 (-6602 5100);
PAINT GREEN (-6602 5100);
DISPLAY INVISIBLE (-6602 5100);
FORCEADD TAP..6
(-6600 5000);
FORCEPROP 3 LASTPIN (-6550 5000) SIG_NAME P5E_CPU1_P0_RX_DP<10>
J 0
(-6540 5010);
DISPLAY 0.659574 (-6540 5010);
PAINT MONO (-6540 5010);
DISPLAY INVISIBLE (-6540 5010);
FORCEPROP 1 LASTPIN (-6550 5000) BN 10
J 0
(-6602 5008);
DISPLAY 0.489362 (-6602 5008);
PAINT MONO (-6602 5008);
FORCEPROP 2 LAST CDS_LIB standard
J 0
(-6600 5000);
DISPLAY INVISIBLE (-6600 5000);
FORCEPROP 1 LAST BODY_TYPE PLUMBING
J 0
(-6600 4950);
DISPLAY 0.574468 (-6600 4950);
PAINT GREEN (-6600 4950);
DISPLAY INVISIBLE (-6600 4950);
FORCEPROP 1 LAST HDL_TAP TRUE
J 0
(-6275 4875);
DISPLAY 0.574468 (-6275 4875);
PAINT GREEN (-6275 4875);
DISPLAY INVISIBLE (-6275 4875);
FORCEPROP 1 LAST PATH I328
J 0
(-6602 5000);
DISPLAY 0.872340 (-6602 5000);
PAINT GREEN (-6602 5000);
DISPLAY INVISIBLE (-6602 5000);
FORCEADD TAP..6
(-6600 4800);
FORCEPROP 3 LASTPIN (-6550 4800) SIG_NAME P5E_CPU1_P0_RX_DP<8>
J 0
(-6540 4810);
DISPLAY 0.659574 (-6540 4810);
PAINT MONO (-6540 4810);
DISPLAY INVISIBLE (-6540 4810);
FORCEPROP 1 LASTPIN (-6550 4800) BN 8
J 0
(-6602 4808);
DISPLAY 0.489362 (-6602 4808);
PAINT MONO (-6602 4808);
FORCEPROP 2 LAST CDS_LIB standard
J 0
(-6600 4800);
DISPLAY INVISIBLE (-6600 4800);
FORCEPROP 1 LAST BODY_TYPE PLUMBING
J 0
(-6600 4750);
DISPLAY 0.574468 (-6600 4750);
PAINT GREEN (-6600 4750);
DISPLAY INVISIBLE (-6600 4750);
FORCEPROP 1 LAST HDL_TAP TRUE
J 0
(-6275 4675);
DISPLAY 0.574468 (-6275 4675);
PAINT GREEN (-6275 4675);
DISPLAY INVISIBLE (-6275 4675);
FORCEPROP 1 LAST PATH I329
J 0
(-6602 4800);
DISPLAY 0.872340 (-6602 4800);
PAINT GREEN (-6602 4800);
DISPLAY INVISIBLE (-6602 4800);
FORCEADD TAP..6
(-6600 4900);
FORCEPROP 3 LASTPIN (-6550 4900) SIG_NAME P5E_CPU1_P0_RX_DP<9>
J 0
(-6540 4910);
DISPLAY 0.659574 (-6540 4910);
PAINT MONO (-6540 4910);
DISPLAY INVISIBLE (-6540 4910);
FORCEPROP 1 LASTPIN (-6550 4900) BN 9
J 0
(-6602 4908);
DISPLAY 0.489362 (-6602 4908);
PAINT MONO (-6602 4908);
FORCEPROP 2 LAST CDS_LIB standard
J 0
(-6600 4900);
DISPLAY INVISIBLE (-6600 4900);
FORCEPROP 1 LAST BODY_TYPE PLUMBING
J 0
(-6600 4850);
DISPLAY 0.574468 (-6600 4850);
PAINT GREEN (-6600 4850);
DISPLAY INVISIBLE (-6600 4850);
FORCEPROP 1 LAST HDL_TAP TRUE
J 0
(-6275 4775);
DISPLAY 0.574468 (-6275 4775);
PAINT GREEN (-6275 4775);
DISPLAY INVISIBLE (-6275 4775);
FORCEPROP 1 LAST PATH I330
J 0
(-6602 4900);
DISPLAY 0.872340 (-6602 4900);
PAINT GREEN (-6602 4900);
DISPLAY INVISIBLE (-6602 4900);
FORCEADD TAP..6
(-6600 4700);
FORCEPROP 3 LASTPIN (-6550 4700) SIG_NAME P5E_CPU1_P0_RX_DP<7>
J 0
(-6540 4710);
DISPLAY 0.659574 (-6540 4710);
PAINT MONO (-6540 4710);
DISPLAY INVISIBLE (-6540 4710);
FORCEPROP 1 LASTPIN (-6550 4700) BN 7
J 0
(-6602 4708);
DISPLAY 0.489362 (-6602 4708);
PAINT MONO (-6602 4708);
FORCEPROP 2 LAST CDS_LIB standard
J 0
(-6600 4700);
DISPLAY INVISIBLE (-6600 4700);
FORCEPROP 1 LAST BODY_TYPE PLUMBING
J 0
(-6600 4650);
DISPLAY 0.574468 (-6600 4650);
PAINT GREEN (-6600 4650);
DISPLAY INVISIBLE (-6600 4650);
FORCEPROP 1 LAST HDL_TAP TRUE
J 0
(-6275 4575);
DISPLAY 0.574468 (-6275 4575);
PAINT GREEN (-6275 4575);
DISPLAY INVISIBLE (-6275 4575);
FORCEPROP 1 LAST PATH I331
J 0
(-6602 4700);
DISPLAY 0.872340 (-6602 4700);
PAINT GREEN (-6602 4700);
DISPLAY INVISIBLE (-6602 4700);
FORCEADD TAP..6
(-6600 4600);
FORCEPROP 3 LASTPIN (-6550 4600) SIG_NAME P5E_CPU1_P0_RX_DP<6>
J 0
(-6540 4610);
DISPLAY 0.659574 (-6540 4610);
PAINT MONO (-6540 4610);
DISPLAY INVISIBLE (-6540 4610);
FORCEPROP 1 LASTPIN (-6550 4600) BN 6
J 0
(-6602 4608);
DISPLAY 0.489362 (-6602 4608);
PAINT MONO (-6602 4608);
FORCEPROP 2 LAST CDS_LIB standard
J 0
(-6600 4600);
DISPLAY INVISIBLE (-6600 4600);
FORCEPROP 1 LAST BODY_TYPE PLUMBING
J 0
(-6600 4550);
DISPLAY 0.574468 (-6600 4550);
PAINT GREEN (-6600 4550);
DISPLAY INVISIBLE (-6600 4550);
FORCEPROP 1 LAST HDL_TAP TRUE
J 0
(-6275 4475);
DISPLAY 0.574468 (-6275 4475);
PAINT GREEN (-6275 4475);
DISPLAY INVISIBLE (-6275 4475);
FORCEPROP 1 LAST PATH I332
J 0
(-6602 4600);
DISPLAY 0.872340 (-6602 4600);
PAINT GREEN (-6602 4600);
DISPLAY INVISIBLE (-6602 4600);
FORCEADD TAP..6
(-6600 4400);
FORCEPROP 3 LASTPIN (-6550 4400) SIG_NAME P5E_CPU1_P0_RX_DP<4>
J 0
(-6540 4410);
DISPLAY 0.659574 (-6540 4410);
PAINT MONO (-6540 4410);
DISPLAY INVISIBLE (-6540 4410);
FORCEPROP 1 LASTPIN (-6550 4400) BN 4
J 0
(-6602 4408);
DISPLAY 0.489362 (-6602 4408);
PAINT MONO (-6602 4408);
FORCEPROP 2 LAST CDS_LIB standard
J 0
(-6600 4400);
DISPLAY INVISIBLE (-6600 4400);
FORCEPROP 1 LAST BODY_TYPE PLUMBING
J 0
(-6600 4350);
DISPLAY 0.574468 (-6600 4350);
PAINT GREEN (-6600 4350);
DISPLAY INVISIBLE (-6600 4350);
FORCEPROP 1 LAST HDL_TAP TRUE
J 0
(-6275 4275);
DISPLAY 0.574468 (-6275 4275);
PAINT GREEN (-6275 4275);
DISPLAY INVISIBLE (-6275 4275);
FORCEPROP 1 LAST PATH I333
J 0
(-6602 4400);
DISPLAY 0.872340 (-6602 4400);
PAINT GREEN (-6602 4400);
DISPLAY INVISIBLE (-6602 4400);
FORCEADD TAP..6
(-6600 4500);
FORCEPROP 3 LASTPIN (-6550 4500) SIG_NAME P5E_CPU1_P0_RX_DP<5>
J 0
(-6540 4510);
DISPLAY 0.659574 (-6540 4510);
PAINT MONO (-6540 4510);
DISPLAY INVISIBLE (-6540 4510);
FORCEPROP 1 LASTPIN (-6550 4500) BN 5
J 0
(-6602 4508);
DISPLAY 0.489362 (-6602 4508);
PAINT MONO (-6602 4508);
FORCEPROP 2 LAST CDS_LIB standard
J 0
(-6600 4500);
DISPLAY INVISIBLE (-6600 4500);
FORCEPROP 1 LAST BODY_TYPE PLUMBING
J 0
(-6600 4450);
DISPLAY 0.574468 (-6600 4450);
PAINT GREEN (-6600 4450);
DISPLAY INVISIBLE (-6600 4450);
FORCEPROP 1 LAST HDL_TAP TRUE
J 0
(-6275 4375);
DISPLAY 0.574468 (-6275 4375);
PAINT GREEN (-6275 4375);
DISPLAY INVISIBLE (-6275 4375);
FORCEPROP 1 LAST PATH I334
J 0
(-6602 4500);
DISPLAY 0.872340 (-6602 4500);
PAINT GREEN (-6602 4500);
DISPLAY INVISIBLE (-6602 4500);
FORCEADD TAP..6
(-6600 4300);
FORCEPROP 3 LASTPIN (-6550 4300) SIG_NAME P5E_CPU1_P0_RX_DP<3>
J 0
(-6540 4310);
DISPLAY 0.659574 (-6540 4310);
PAINT MONO (-6540 4310);
DISPLAY INVISIBLE (-6540 4310);
FORCEPROP 1 LASTPIN (-6550 4300) BN 3
J 0
(-6602 4308);
DISPLAY 0.489362 (-6602 4308);
PAINT MONO (-6602 4308);
FORCEPROP 2 LAST CDS_LIB standard
J 0
(-6600 4300);
DISPLAY INVISIBLE (-6600 4300);
FORCEPROP 1 LAST BODY_TYPE PLUMBING
J 0
(-6600 4250);
DISPLAY 0.574468 (-6600 4250);
PAINT GREEN (-6600 4250);
DISPLAY INVISIBLE (-6600 4250);
FORCEPROP 1 LAST HDL_TAP TRUE
J 0
(-6275 4175);
DISPLAY 0.574468 (-6275 4175);
PAINT GREEN (-6275 4175);
DISPLAY INVISIBLE (-6275 4175);
FORCEPROP 1 LAST PATH I335
J 0
(-6602 4300);
DISPLAY 0.872340 (-6602 4300);
PAINT GREEN (-6602 4300);
DISPLAY INVISIBLE (-6602 4300);
FORCEADD TAP..6
(-6600 4200);
FORCEPROP 3 LASTPIN (-6550 4200) SIG_NAME P5E_CPU1_P0_RX_DP<2>
J 0
(-6540 4210);
DISPLAY 0.659574 (-6540 4210);
PAINT MONO (-6540 4210);
DISPLAY INVISIBLE (-6540 4210);
FORCEPROP 1 LASTPIN (-6550 4200) BN 2
J 0
(-6602 4208);
DISPLAY 0.489362 (-6602 4208);
PAINT MONO (-6602 4208);
FORCEPROP 2 LAST CDS_LIB standard
J 0
(-6600 4200);
DISPLAY INVISIBLE (-6600 4200);
FORCEPROP 1 LAST BODY_TYPE PLUMBING
J 0
(-6600 4150);
DISPLAY 0.574468 (-6600 4150);
PAINT GREEN (-6600 4150);
DISPLAY INVISIBLE (-6600 4150);
FORCEPROP 1 LAST HDL_TAP TRUE
J 0
(-6275 4075);
DISPLAY 0.574468 (-6275 4075);
PAINT GREEN (-6275 4075);
DISPLAY INVISIBLE (-6275 4075);
FORCEPROP 1 LAST PATH I336
J 0
(-6602 4200);
DISPLAY 0.872340 (-6602 4200);
PAINT GREEN (-6602 4200);
DISPLAY INVISIBLE (-6602 4200);
FORCEADD TAP..6
(-6600 4100);
FORCEPROP 3 LASTPIN (-6550 4100) SIG_NAME P5E_CPU1_P0_RX_DP<1>
J 0
(-6540 4110);
DISPLAY 0.659574 (-6540 4110);
PAINT MONO (-6540 4110);
DISPLAY INVISIBLE (-6540 4110);
FORCEPROP 1 LASTPIN (-6550 4100) BN 1
J 0
(-6602 4108);
DISPLAY 0.489362 (-6602 4108);
PAINT MONO (-6602 4108);
FORCEPROP 2 LAST CDS_LIB standard
J 0
(-6600 4100);
DISPLAY INVISIBLE (-6600 4100);
FORCEPROP 1 LAST BODY_TYPE PLUMBING
J 0
(-6600 4050);
DISPLAY 0.574468 (-6600 4050);
PAINT GREEN (-6600 4050);
DISPLAY INVISIBLE (-6600 4050);
FORCEPROP 1 LAST HDL_TAP TRUE
J 0
(-6275 3975);
DISPLAY 0.574468 (-6275 3975);
PAINT GREEN (-6275 3975);
DISPLAY INVISIBLE (-6275 3975);
FORCEPROP 1 LAST PATH I337
J 0
(-6602 4100);
DISPLAY 0.872340 (-6602 4100);
PAINT GREEN (-6602 4100);
DISPLAY INVISIBLE (-6602 4100);
FORCEADD TAP..6
(-6600 4000);
FORCEPROP 3 LASTPIN (-6550 4000) SIG_NAME P5E_CPU1_P0_RX_DP<0>
J 0
(-6540 4010);
DISPLAY 0.659574 (-6540 4010);
PAINT MONO (-6540 4010);
DISPLAY INVISIBLE (-6540 4010);
FORCEPROP 1 LASTPIN (-6550 4000) BN 0
J 0
(-6602 4008);
DISPLAY 0.489362 (-6602 4008);
PAINT MONO (-6602 4008);
FORCEPROP 2 LAST CDS_LIB standard
J 0
(-6600 4000);
DISPLAY INVISIBLE (-6600 4000);
FORCEPROP 1 LAST BODY_TYPE PLUMBING
J 0
(-6600 3950);
DISPLAY 0.574468 (-6600 3950);
PAINT GREEN (-6600 3950);
DISPLAY INVISIBLE (-6600 3950);
FORCEPROP 1 LAST HDL_TAP TRUE
J 0
(-6275 3875);
DISPLAY 0.574468 (-6275 3875);
PAINT GREEN (-6275 3875);
DISPLAY INVISIBLE (-6275 3875);
FORCEPROP 1 LAST PATH I338
J 0
(-6602 4000);
DISPLAY 0.872340 (-6602 4000);
PAINT GREEN (-6602 4000);
DISPLAY INVISIBLE (-6602 4000);
FORCEADD OFFPAGE..1
(-7550 5725);
FORCEPROP 2 LAST $XR0 116 
J 0
(-7802 5725);
DISPLAY 0.638298 (-7802 5725);
PAINT MONO (-7802 5725);
FORCEPROP 2 LAST PATH I339
J 0
(-7800 5775);
DISPLAY 0.680851 (-7800 5775);
DISPLAY INVISIBLE (-7800 5775);
FORCEPROP 2 LAST CDS_LIB standard
J 0
(-7550 5725);
DISPLAY INVISIBLE (-7550 5725);
FORCEPROP 1 LAST OFFPAGE TRUE
J 0
(-7225 5600);
DISPLAY 0.872340 (-7225 5600);
PAINT GREEN (-7225 5600);
DISPLAY INVISIBLE (-7225 5600);
FORCEPROP 1 LAST COMMENT_BODY TRUE
J 0
(-7425 5625);
DISPLAY 0.872340 (-7425 5625);
PAINT GREEN (-7425 5625);
DISPLAY INVISIBLE (-7425 5625);
FORCEADD TAP..6
R 2
(-2800 4400);
FORCEPROP 3 LASTPIN (-2850 4400) SIG_NAME P5E_CPU1_P0_TX_DN<4>
J 0
(-2840 4410);
DISPLAY 0.659574 (-2840 4410);
PAINT MONO (-2840 4410);
DISPLAY INVISIBLE (-2840 4410);
FORCEPROP 1 LASTPIN (-2850 4400) BN 4
J 2
(-2798 4408);
DISPLAY 0.489362 (-2798 4408);
PAINT MONO (-2798 4408);
FORCEPROP 2 LAST CDS_LIB standard
J 0
(-2800 4400);
DISPLAY INVISIBLE (-2800 4400);
FORCEPROP 2 LAST BOM_COST IO_SLOT
J 0
(-3300 4500);
DISPLAY 0.829787 (-3300 4500);
DISPLAY INVISIBLE (-3300 4500);
FORCEPROP 1 LAST BODY_TYPE PLUMBING
J 2
(-2800 4350);
DISPLAY 0.702128 (-2800 4350);
PAINT GREEN (-2800 4350);
DISPLAY INVISIBLE (-2800 4350);
FORCEPROP 1 LAST HDL_TAP TRUE
J 2
(-3125 4275);
DISPLAY 0.702128 (-3125 4275);
PAINT GREEN (-3125 4275);
DISPLAY INVISIBLE (-3125 4275);
FORCEPROP 1 LAST PATH I340
J 2
(-2798 4400);
DISPLAY 0.872340 (-2798 4400);
PAINT GREEN (-2798 4400);
DISPLAY INVISIBLE (-2798 4400);
FORCEPROP 2 LAST ROOM RISER1
J 0
(-3300 4450);
DISPLAY 0.829787 (-3300 4450);
PAINT RED (-3300 4450);
DISPLAY INVISIBLE (-3300 4450);
FORCEADD OFFPAGE..2
(-1825 5725);
FORCEPROP 2 LAST $XR0 65 
J 0
(-1636 5725);
DISPLAY 0.638298 (-1636 5725);
PAINT MONO (-1636 5725);
FORCEPROP 2 LAST PATH I341
J 0
(-1625 5775);
DISPLAY 0.680851 (-1625 5775);
DISPLAY INVISIBLE (-1625 5775);
FORCEPROP 2 LAST CDS_LIB standard
J 0
(-1825 5725);
DISPLAY INVISIBLE (-1825 5725);
FORCEPROP 1 LAST OFFPAGE TRUE
J 0
(-1500 5600);
DISPLAY 0.872340 (-1500 5600);
PAINT GREEN (-1500 5600);
DISPLAY INVISIBLE (-1500 5600);
FORCEPROP 1 LAST COMMENT_BODY TRUE
J 0
(-1870 5630);
DISPLAY 0.872340 (-1870 5630);
PAINT GREEN (-1870 5630);
DISPLAY INVISIBLE (-1870 5630);
FORCEADD TAP..6
R 2
(-2800 5500);
FORCEPROP 3 LASTPIN (-2850 5500) SIG_NAME P5E_CPU1_P0_TX_DN<15>
J 0
(-2840 5510);
DISPLAY 0.659574 (-2840 5510);
PAINT MONO (-2840 5510);
DISPLAY INVISIBLE (-2840 5510);
FORCEPROP 1 LASTPIN (-2850 5500) BN 15
J 2
(-2798 5508);
DISPLAY 0.489362 (-2798 5508);
PAINT MONO (-2798 5508);
FORCEPROP 2 LAST BOM_COST IO_SLOT
J 0
(-3300 5600);
DISPLAY 0.829787 (-3300 5600);
DISPLAY INVISIBLE (-3300 5600);
FORCEPROP 2 LAST CDS_LIB mstr_standard
J 0
(-2800 5500);
DISPLAY INVISIBLE (-2800 5500);
FORCEPROP 1 LAST BODY_TYPE PLUMBING
J 2
(-2800 5450);
DISPLAY 0.702128 (-2800 5450);
PAINT GREEN (-2800 5450);
DISPLAY INVISIBLE (-2800 5450);
FORCEPROP 1 LAST HDL_TAP TRUE
J 2
(-3125 5375);
DISPLAY 0.702128 (-3125 5375);
PAINT GREEN (-3125 5375);
DISPLAY INVISIBLE (-3125 5375);
FORCEPROP 1 LAST PATH I342
J 2
(-2798 5500);
DISPLAY 0.872340 (-2798 5500);
PAINT GREEN (-2798 5500);
DISPLAY INVISIBLE (-2798 5500);
FORCEPROP 2 LAST ROOM RISER1
J 0
(-3300 5550);
DISPLAY 0.829787 (-3300 5550);
PAINT RED (-3300 5550);
DISPLAY INVISIBLE (-3300 5550);
FORCEADD TAP..6
R 2
(-2800 5400);
FORCEPROP 3 LASTPIN (-2850 5400) SIG_NAME P5E_CPU1_P0_TX_DN<14>
J 0
(-2840 5410);
DISPLAY 0.659574 (-2840 5410);
PAINT MONO (-2840 5410);
DISPLAY INVISIBLE (-2840 5410);
FORCEPROP 1 LASTPIN (-2850 5400) BN 14
J 2
(-2798 5408);
DISPLAY 0.489362 (-2798 5408);
PAINT MONO (-2798 5408);
FORCEPROP 2 LAST CDS_LIB mstr_standard
J 0
(-2800 5400);
DISPLAY INVISIBLE (-2800 5400);
FORCEPROP 2 LAST BOM_COST IO_SLOT
J 0
(-3300 5500);
DISPLAY 0.829787 (-3300 5500);
DISPLAY INVISIBLE (-3300 5500);
FORCEPROP 1 LAST BODY_TYPE PLUMBING
J 2
(-2800 5350);
DISPLAY 0.702128 (-2800 5350);
PAINT GREEN (-2800 5350);
DISPLAY INVISIBLE (-2800 5350);
FORCEPROP 1 LAST HDL_TAP TRUE
J 2
(-3125 5275);
DISPLAY 0.702128 (-3125 5275);
PAINT GREEN (-3125 5275);
DISPLAY INVISIBLE (-3125 5275);
FORCEPROP 1 LAST PATH I343
J 2
(-2798 5400);
DISPLAY 0.872340 (-2798 5400);
PAINT GREEN (-2798 5400);
DISPLAY INVISIBLE (-2798 5400);
FORCEPROP 2 LAST ROOM RISER1
J 0
(-3300 5450);
DISPLAY 0.829787 (-3300 5450);
PAINT RED (-3300 5450);
DISPLAY INVISIBLE (-3300 5450);
FORCEADD TAP..6
R 2
(-2800 5300);
FORCEPROP 3 LASTPIN (-2850 5300) SIG_NAME P5E_CPU1_P0_TX_DN<13>
J 0
(-2840 5310);
DISPLAY 0.659574 (-2840 5310);
PAINT MONO (-2840 5310);
DISPLAY INVISIBLE (-2840 5310);
FORCEPROP 1 LASTPIN (-2850 5300) BN 13
J 2
(-2798 5308);
DISPLAY 0.489362 (-2798 5308);
PAINT MONO (-2798 5308);
FORCEPROP 2 LAST CDS_LIB standard
J 0
(-2800 5300);
DISPLAY INVISIBLE (-2800 5300);
FORCEPROP 2 LAST BOM_COST IO_SLOT
J 0
(-3300 5400);
DISPLAY 0.829787 (-3300 5400);
DISPLAY INVISIBLE (-3300 5400);
FORCEPROP 1 LAST BODY_TYPE PLUMBING
J 2
(-2800 5250);
DISPLAY 0.702128 (-2800 5250);
PAINT GREEN (-2800 5250);
DISPLAY INVISIBLE (-2800 5250);
FORCEPROP 1 LAST HDL_TAP TRUE
J 2
(-3125 5175);
DISPLAY 0.702128 (-3125 5175);
PAINT GREEN (-3125 5175);
DISPLAY INVISIBLE (-3125 5175);
FORCEPROP 1 LAST PATH I344
J 2
(-2798 5300);
DISPLAY 0.872340 (-2798 5300);
PAINT GREEN (-2798 5300);
DISPLAY INVISIBLE (-2798 5300);
FORCEPROP 2 LAST ROOM RISER1
J 0
(-3300 5350);
DISPLAY 0.829787 (-3300 5350);
PAINT RED (-3300 5350);
DISPLAY INVISIBLE (-3300 5350);
FORCEADD TAP..6
R 2
(-2800 5200);
FORCEPROP 3 LASTPIN (-2850 5200) SIG_NAME P5E_CPU1_P0_TX_DN<12>
J 0
(-2840 5210);
DISPLAY 0.659574 (-2840 5210);
PAINT MONO (-2840 5210);
DISPLAY INVISIBLE (-2840 5210);
FORCEPROP 1 LASTPIN (-2850 5200) BN 12
J 2
(-2798 5208);
DISPLAY 0.489362 (-2798 5208);
PAINT MONO (-2798 5208);
FORCEPROP 2 LAST CDS_LIB standard
J 0
(-2800 5200);
DISPLAY INVISIBLE (-2800 5200);
FORCEPROP 2 LAST BOM_COST IO_SLOT
J 0
(-3300 5300);
DISPLAY 0.829787 (-3300 5300);
DISPLAY INVISIBLE (-3300 5300);
FORCEPROP 1 LAST BODY_TYPE PLUMBING
J 2
(-2800 5150);
DISPLAY 0.702128 (-2800 5150);
PAINT GREEN (-2800 5150);
DISPLAY INVISIBLE (-2800 5150);
FORCEPROP 1 LAST HDL_TAP TRUE
J 2
(-3125 5075);
DISPLAY 0.702128 (-3125 5075);
PAINT GREEN (-3125 5075);
DISPLAY INVISIBLE (-3125 5075);
FORCEPROP 1 LAST PATH I345
J 2
(-2798 5200);
DISPLAY 0.872340 (-2798 5200);
PAINT GREEN (-2798 5200);
DISPLAY INVISIBLE (-2798 5200);
FORCEPROP 2 LAST ROOM RISER1
J 0
(-3300 5250);
DISPLAY 0.829787 (-3300 5250);
PAINT RED (-3300 5250);
DISPLAY INVISIBLE (-3300 5250);
FORCEADD TAP..6
R 2
(-2800 5100);
FORCEPROP 3 LASTPIN (-2850 5100) SIG_NAME P5E_CPU1_P0_TX_DN<11>
J 0
(-2840 5110);
DISPLAY 0.659574 (-2840 5110);
PAINT MONO (-2840 5110);
DISPLAY INVISIBLE (-2840 5110);
FORCEPROP 1 LASTPIN (-2850 5100) BN 11
J 2
(-2798 5108);
DISPLAY 0.489362 (-2798 5108);
PAINT MONO (-2798 5108);
FORCEPROP 2 LAST CDS_LIB standard
J 0
(-2800 5100);
DISPLAY INVISIBLE (-2800 5100);
FORCEPROP 2 LAST BOM_COST IO_SLOT
J 0
(-3300 5200);
DISPLAY 0.829787 (-3300 5200);
DISPLAY INVISIBLE (-3300 5200);
FORCEPROP 1 LAST BODY_TYPE PLUMBING
J 2
(-2800 5050);
DISPLAY 0.702128 (-2800 5050);
PAINT GREEN (-2800 5050);
DISPLAY INVISIBLE (-2800 5050);
FORCEPROP 1 LAST HDL_TAP TRUE
J 2
(-3125 4975);
DISPLAY 0.702128 (-3125 4975);
PAINT GREEN (-3125 4975);
DISPLAY INVISIBLE (-3125 4975);
FORCEPROP 1 LAST PATH I346
J 2
(-2798 5100);
DISPLAY 0.872340 (-2798 5100);
PAINT GREEN (-2798 5100);
DISPLAY INVISIBLE (-2798 5100);
FORCEPROP 2 LAST ROOM RISER1
J 0
(-3300 5150);
DISPLAY 0.829787 (-3300 5150);
PAINT RED (-3300 5150);
DISPLAY INVISIBLE (-3300 5150);
FORCEADD TAP..6
R 2
(-2800 5000);
FORCEPROP 3 LASTPIN (-2850 5000) SIG_NAME P5E_CPU1_P0_TX_DN<10>
J 0
(-2840 5010);
DISPLAY 0.659574 (-2840 5010);
PAINT MONO (-2840 5010);
DISPLAY INVISIBLE (-2840 5010);
FORCEPROP 1 LASTPIN (-2850 5000) BN 10
J 2
(-2798 5008);
DISPLAY 0.489362 (-2798 5008);
PAINT MONO (-2798 5008);
FORCEPROP 2 LAST CDS_LIB standard
J 0
(-2800 5000);
DISPLAY INVISIBLE (-2800 5000);
FORCEPROP 2 LAST BOM_COST IO_SLOT
J 0
(-3300 5100);
DISPLAY 0.829787 (-3300 5100);
DISPLAY INVISIBLE (-3300 5100);
FORCEPROP 1 LAST BODY_TYPE PLUMBING
J 2
(-2800 4950);
DISPLAY 0.702128 (-2800 4950);
PAINT GREEN (-2800 4950);
DISPLAY INVISIBLE (-2800 4950);
FORCEPROP 1 LAST HDL_TAP TRUE
J 2
(-3125 4875);
DISPLAY 0.702128 (-3125 4875);
PAINT GREEN (-3125 4875);
DISPLAY INVISIBLE (-3125 4875);
FORCEPROP 1 LAST PATH I347
J 2
(-2798 5000);
DISPLAY 0.872340 (-2798 5000);
PAINT GREEN (-2798 5000);
DISPLAY INVISIBLE (-2798 5000);
FORCEPROP 2 LAST ROOM RISER1
J 0
(-3300 5050);
DISPLAY 0.829787 (-3300 5050);
PAINT RED (-3300 5050);
DISPLAY INVISIBLE (-3300 5050);
FORCEADD TAP..6
R 2
(-2800 4900);
FORCEPROP 3 LASTPIN (-2850 4900) SIG_NAME P5E_CPU1_P0_TX_DN<9>
J 0
(-2840 4910);
DISPLAY 0.659574 (-2840 4910);
PAINT MONO (-2840 4910);
DISPLAY INVISIBLE (-2840 4910);
FORCEPROP 1 LASTPIN (-2850 4900) BN 9
J 2
(-2798 4908);
DISPLAY 0.489362 (-2798 4908);
PAINT MONO (-2798 4908);
FORCEPROP 2 LAST CDS_LIB standard
J 0
(-2800 4900);
DISPLAY INVISIBLE (-2800 4900);
FORCEPROP 2 LAST BOM_COST IO_SLOT
J 0
(-3300 5000);
DISPLAY 0.829787 (-3300 5000);
DISPLAY INVISIBLE (-3300 5000);
FORCEPROP 1 LAST BODY_TYPE PLUMBING
J 2
(-2800 4850);
DISPLAY 0.702128 (-2800 4850);
PAINT GREEN (-2800 4850);
DISPLAY INVISIBLE (-2800 4850);
FORCEPROP 1 LAST HDL_TAP TRUE
J 2
(-3125 4775);
DISPLAY 0.702128 (-3125 4775);
PAINT GREEN (-3125 4775);
DISPLAY INVISIBLE (-3125 4775);
FORCEPROP 1 LAST PATH I348
J 2
(-2798 4900);
DISPLAY 0.872340 (-2798 4900);
PAINT GREEN (-2798 4900);
DISPLAY INVISIBLE (-2798 4900);
FORCEPROP 2 LAST ROOM RISER1
J 0
(-3300 4950);
DISPLAY 0.829787 (-3300 4950);
PAINT RED (-3300 4950);
DISPLAY INVISIBLE (-3300 4950);
FORCEADD TAP..6
R 2
(-2800 4700);
FORCEPROP 3 LASTPIN (-2850 4700) SIG_NAME P5E_CPU1_P0_TX_DN<7>
J 0
(-2840 4710);
DISPLAY 0.659574 (-2840 4710);
PAINT MONO (-2840 4710);
DISPLAY INVISIBLE (-2840 4710);
FORCEPROP 1 LASTPIN (-2850 4700) BN 7
J 2
(-2798 4708);
DISPLAY 0.489362 (-2798 4708);
PAINT MONO (-2798 4708);
FORCEPROP 2 LAST CDS_LIB standard
J 0
(-2800 4700);
DISPLAY INVISIBLE (-2800 4700);
FORCEPROP 2 LAST BOM_COST IO_SLOT
J 0
(-3300 4800);
DISPLAY 0.829787 (-3300 4800);
DISPLAY INVISIBLE (-3300 4800);
FORCEPROP 1 LAST BODY_TYPE PLUMBING
J 2
(-2800 4650);
DISPLAY 0.702128 (-2800 4650);
PAINT GREEN (-2800 4650);
DISPLAY INVISIBLE (-2800 4650);
FORCEPROP 1 LAST HDL_TAP TRUE
J 2
(-3125 4575);
DISPLAY 0.702128 (-3125 4575);
PAINT GREEN (-3125 4575);
DISPLAY INVISIBLE (-3125 4575);
FORCEPROP 1 LAST PATH I349
J 2
(-2798 4700);
DISPLAY 0.872340 (-2798 4700);
PAINT GREEN (-2798 4700);
DISPLAY INVISIBLE (-2798 4700);
FORCEPROP 2 LAST ROOM RISER1
J 0
(-3300 4750);
DISPLAY 0.829787 (-3300 4750);
PAINT RED (-3300 4750);
DISPLAY INVISIBLE (-3300 4750);
FORCEADD TAP..6
R 2
(-2800 4800);
FORCEPROP 3 LASTPIN (-2850 4800) SIG_NAME P5E_CPU1_P0_TX_DN<8>
J 0
(-2840 4810);
DISPLAY 0.659574 (-2840 4810);
PAINT MONO (-2840 4810);
DISPLAY INVISIBLE (-2840 4810);
FORCEPROP 1 LASTPIN (-2850 4800) BN 8
J 2
(-2798 4808);
DISPLAY 0.489362 (-2798 4808);
PAINT MONO (-2798 4808);
FORCEPROP 2 LAST CDS_LIB standard
J 0
(-2800 4800);
DISPLAY INVISIBLE (-2800 4800);
FORCEPROP 2 LAST BOM_COST IO_SLOT
J 0
(-3300 4900);
DISPLAY 0.829787 (-3300 4900);
DISPLAY INVISIBLE (-3300 4900);
FORCEPROP 1 LAST BODY_TYPE PLUMBING
J 2
(-2800 4750);
DISPLAY 0.702128 (-2800 4750);
PAINT GREEN (-2800 4750);
DISPLAY INVISIBLE (-2800 4750);
FORCEPROP 1 LAST HDL_TAP TRUE
J 2
(-3125 4675);
DISPLAY 0.702128 (-3125 4675);
PAINT GREEN (-3125 4675);
DISPLAY INVISIBLE (-3125 4675);
FORCEPROP 1 LAST PATH I350
J 2
(-2798 4800);
DISPLAY 0.872340 (-2798 4800);
PAINT GREEN (-2798 4800);
DISPLAY INVISIBLE (-2798 4800);
FORCEPROP 2 LAST ROOM RISER1
J 0
(-3300 4850);
DISPLAY 0.829787 (-3300 4850);
PAINT RED (-3300 4850);
DISPLAY INVISIBLE (-3300 4850);
FORCEADD TAP..6
R 2
(-2800 4600);
FORCEPROP 3 LASTPIN (-2850 4600) SIG_NAME P5E_CPU1_P0_TX_DN<6>
J 0
(-2840 4610);
DISPLAY 0.659574 (-2840 4610);
PAINT MONO (-2840 4610);
DISPLAY INVISIBLE (-2840 4610);
FORCEPROP 1 LASTPIN (-2850 4600) BN 6
J 2
(-2798 4608);
DISPLAY 0.489362 (-2798 4608);
PAINT MONO (-2798 4608);
FORCEPROP 2 LAST CDS_LIB standard
J 0
(-2800 4600);
DISPLAY INVISIBLE (-2800 4600);
FORCEPROP 2 LAST BOM_COST IO_SLOT
J 0
(-3300 4700);
DISPLAY 0.829787 (-3300 4700);
DISPLAY INVISIBLE (-3300 4700);
FORCEPROP 1 LAST BODY_TYPE PLUMBING
J 2
(-2800 4550);
DISPLAY 0.702128 (-2800 4550);
PAINT GREEN (-2800 4550);
DISPLAY INVISIBLE (-2800 4550);
FORCEPROP 1 LAST HDL_TAP TRUE
J 2
(-3125 4475);
DISPLAY 0.702128 (-3125 4475);
PAINT GREEN (-3125 4475);
DISPLAY INVISIBLE (-3125 4475);
FORCEPROP 1 LAST PATH I351
J 2
(-2798 4600);
DISPLAY 0.872340 (-2798 4600);
PAINT GREEN (-2798 4600);
DISPLAY INVISIBLE (-2798 4600);
FORCEPROP 2 LAST ROOM RISER1
J 0
(-3300 4650);
DISPLAY 0.829787 (-3300 4650);
PAINT RED (-3300 4650);
DISPLAY INVISIBLE (-3300 4650);
FORCEADD TAP..6
R 2
(-2800 4500);
FORCEPROP 3 LASTPIN (-2850 4500) SIG_NAME P5E_CPU1_P0_TX_DN<5>
J 0
(-2840 4510);
DISPLAY 0.659574 (-2840 4510);
PAINT MONO (-2840 4510);
DISPLAY INVISIBLE (-2840 4510);
FORCEPROP 1 LASTPIN (-2850 4500) BN 5
J 2
(-2798 4508);
DISPLAY 0.489362 (-2798 4508);
PAINT MONO (-2798 4508);
FORCEPROP 2 LAST CDS_LIB standard
J 0
(-2800 4500);
DISPLAY INVISIBLE (-2800 4500);
FORCEPROP 2 LAST BOM_COST IO_SLOT
J 0
(-3300 4600);
DISPLAY 0.829787 (-3300 4600);
DISPLAY INVISIBLE (-3300 4600);
FORCEPROP 1 LAST BODY_TYPE PLUMBING
J 2
(-2800 4450);
DISPLAY 0.702128 (-2800 4450);
PAINT GREEN (-2800 4450);
DISPLAY INVISIBLE (-2800 4450);
FORCEPROP 1 LAST HDL_TAP TRUE
J 2
(-3125 4375);
DISPLAY 0.702128 (-3125 4375);
PAINT GREEN (-3125 4375);
DISPLAY INVISIBLE (-3125 4375);
FORCEPROP 1 LAST PATH I352
J 2
(-2798 4500);
DISPLAY 0.872340 (-2798 4500);
PAINT GREEN (-2798 4500);
DISPLAY INVISIBLE (-2798 4500);
FORCEPROP 2 LAST ROOM RISER1
J 0
(-3300 4550);
DISPLAY 0.829787 (-3300 4550);
PAINT RED (-3300 4550);
DISPLAY INVISIBLE (-3300 4550);
FORCEADD TAP..6
R 2
(-2800 4300);
FORCEPROP 3 LASTPIN (-2850 4300) SIG_NAME P5E_CPU1_P0_TX_DN<3>
J 0
(-2840 4310);
DISPLAY 0.659574 (-2840 4310);
PAINT MONO (-2840 4310);
DISPLAY INVISIBLE (-2840 4310);
FORCEPROP 1 LASTPIN (-2850 4300) BN 3
J 2
(-2798 4308);
DISPLAY 0.489362 (-2798 4308);
PAINT MONO (-2798 4308);
FORCEPROP 2 LAST CDS_LIB standard
J 0
(-2800 4300);
DISPLAY INVISIBLE (-2800 4300);
FORCEPROP 2 LAST BOM_COST IO_SLOT
J 0
(-3300 4400);
DISPLAY 0.829787 (-3300 4400);
DISPLAY INVISIBLE (-3300 4400);
FORCEPROP 1 LAST BODY_TYPE PLUMBING
J 2
(-2800 4250);
DISPLAY 0.702128 (-2800 4250);
PAINT GREEN (-2800 4250);
DISPLAY INVISIBLE (-2800 4250);
FORCEPROP 1 LAST HDL_TAP TRUE
J 2
(-3125 4175);
DISPLAY 0.702128 (-3125 4175);
PAINT GREEN (-3125 4175);
DISPLAY INVISIBLE (-3125 4175);
FORCEPROP 1 LAST PATH I353
J 2
(-2798 4300);
DISPLAY 0.872340 (-2798 4300);
PAINT GREEN (-2798 4300);
DISPLAY INVISIBLE (-2798 4300);
FORCEPROP 2 LAST ROOM RISER1
J 0
(-3300 4350);
DISPLAY 0.829787 (-3300 4350);
PAINT RED (-3300 4350);
DISPLAY INVISIBLE (-3300 4350);
FORCEADD TAP..6
R 2
(-2800 4200);
FORCEPROP 3 LASTPIN (-2850 4200) SIG_NAME P5E_CPU1_P0_TX_DN<2>
J 0
(-2840 4210);
DISPLAY 0.659574 (-2840 4210);
PAINT MONO (-2840 4210);
DISPLAY INVISIBLE (-2840 4210);
FORCEPROP 1 LASTPIN (-2850 4200) BN 2
J 2
(-2798 4208);
DISPLAY 0.489362 (-2798 4208);
PAINT MONO (-2798 4208);
FORCEPROP 2 LAST CDS_LIB standard
J 0
(-2800 4200);
DISPLAY INVISIBLE (-2800 4200);
FORCEPROP 2 LAST BOM_COST IO_SLOT
J 0
(-3300 4300);
DISPLAY 0.829787 (-3300 4300);
DISPLAY INVISIBLE (-3300 4300);
FORCEPROP 1 LAST BODY_TYPE PLUMBING
J 2
(-2800 4150);
DISPLAY 0.702128 (-2800 4150);
PAINT GREEN (-2800 4150);
DISPLAY INVISIBLE (-2800 4150);
FORCEPROP 1 LAST HDL_TAP TRUE
J 2
(-3125 4075);
DISPLAY 0.702128 (-3125 4075);
PAINT GREEN (-3125 4075);
DISPLAY INVISIBLE (-3125 4075);
FORCEPROP 1 LAST PATH I354
J 2
(-2798 4200);
DISPLAY 0.872340 (-2798 4200);
PAINT GREEN (-2798 4200);
DISPLAY INVISIBLE (-2798 4200);
FORCEPROP 2 LAST ROOM RISER1
J 0
(-3300 4250);
DISPLAY 0.829787 (-3300 4250);
PAINT RED (-3300 4250);
DISPLAY INVISIBLE (-3300 4250);
FORCEADD TAP..6
R 2
(-2800 4100);
FORCEPROP 3 LASTPIN (-2850 4100) SIG_NAME P5E_CPU1_P0_TX_DN<1>
J 0
(-2840 4110);
DISPLAY 0.659574 (-2840 4110);
PAINT MONO (-2840 4110);
DISPLAY INVISIBLE (-2840 4110);
FORCEPROP 1 LASTPIN (-2850 4100) BN 1
J 2
(-2798 4108);
DISPLAY 0.489362 (-2798 4108);
PAINT MONO (-2798 4108);
FORCEPROP 2 LAST BOM_COST IO_SLOT
J 0
(-3300 4200);
DISPLAY 0.829787 (-3300 4200);
DISPLAY INVISIBLE (-3300 4200);
FORCEPROP 2 LAST CDS_LIB standard
J 0
(-2800 4100);
DISPLAY INVISIBLE (-2800 4100);
FORCEPROP 1 LAST BODY_TYPE PLUMBING
J 2
(-2800 4050);
DISPLAY 0.702128 (-2800 4050);
PAINT GREEN (-2800 4050);
DISPLAY INVISIBLE (-2800 4050);
FORCEPROP 1 LAST HDL_TAP TRUE
J 2
(-3125 3975);
DISPLAY 0.702128 (-3125 3975);
PAINT GREEN (-3125 3975);
DISPLAY INVISIBLE (-3125 3975);
FORCEPROP 1 LAST PATH I355
J 2
(-2798 4100);
DISPLAY 0.872340 (-2798 4100);
PAINT GREEN (-2798 4100);
DISPLAY INVISIBLE (-2798 4100);
FORCEPROP 2 LAST ROOM RISER1
J 0
(-3300 4150);
DISPLAY 0.829787 (-3300 4150);
PAINT RED (-3300 4150);
DISPLAY INVISIBLE (-3300 4150);
FORCEADD TAP..6
R 2
(-2800 4000);
FORCEPROP 3 LASTPIN (-2850 4000) SIG_NAME P5E_CPU1_P0_TX_DN<0>
J 0
(-2840 4010);
DISPLAY 0.659574 (-2840 4010);
PAINT MONO (-2840 4010);
DISPLAY INVISIBLE (-2840 4010);
FORCEPROP 1 LASTPIN (-2850 4000) BN 0
J 2
(-2798 4008);
DISPLAY 0.489362 (-2798 4008);
PAINT MONO (-2798 4008);
FORCEPROP 2 LAST CDS_LIB standard
J 0
(-2800 4000);
DISPLAY INVISIBLE (-2800 4000);
FORCEPROP 2 LAST BOM_COST IO_SLOT
J 0
(-3300 4100);
DISPLAY 0.829787 (-3300 4100);
DISPLAY INVISIBLE (-3300 4100);
FORCEPROP 1 LAST BODY_TYPE PLUMBING
J 2
(-2800 3950);
DISPLAY 0.702128 (-2800 3950);
PAINT GREEN (-2800 3950);
DISPLAY INVISIBLE (-2800 3950);
FORCEPROP 1 LAST HDL_TAP TRUE
J 2
(-3125 3875);
DISPLAY 0.702128 (-3125 3875);
PAINT GREEN (-3125 3875);
DISPLAY INVISIBLE (-3125 3875);
FORCEPROP 1 LAST PATH I356
J 2
(-2798 4000);
DISPLAY 0.872340 (-2798 4000);
PAINT GREEN (-2798 4000);
DISPLAY INVISIBLE (-2798 4000);
FORCEPROP 2 LAST ROOM RISER1
J 0
(-3300 4050);
DISPLAY 0.829787 (-3300 4050);
PAINT RED (-3300 4050);
DISPLAY INVISIBLE (-3300 4050);
FORCEADD QUANTA_TITLE_BLOCK_C..1
(0 0);
FORCEPROP 0 LAST CDS_CON_LAST_MODIFIED Fri Mar 11 14:52:36 2022
J 0
(-1885 15);
DISPLAY INVISIBLE (-1885 15);
FORCEPROP 1 LAST CUSTOM_TXT_CDS <CON_LAST_MODIFIED>
J 0
(-1885 15);
DISPLAY 0.978723 (-1885 15);
FORCEPROP 2 LAST CUSTOM_TXT_CDS <XR_PAGE_TITLE>
J 0
(-7890 5250);
DISPLAY 0.638298 (-7890 5250);
PAINT PINK (-7890 5250);
DISPLAY INVISIBLE (-7890 5250);
FORCEPROP 1 LAST CUSTOM_TXT_CDS <NAME_2>
J 0
(-3175 50);
FORCEPROP 1 LAST CUSTOM_TXT_CDS <NAME_1>
J 0
(-3175 175);
FORCEPROP 1 LAST CUSTOM_TXT_CDS <Q_NUMBER>
J 0
(-1403 103);
DISPLAY 1.212766 (-1403 103);
FORCEPROP 1 LAST CUSTOM_TXT_CDS <Q_PROJ>
J 0
(-2382 102);
DISPLAY 1.212766 (-2382 102);
FORCEPROP 1 LAST CUSTOM_TXT_CDS <Q_REV>
J 0
(-184 103);
DISPLAY 1.212766 (-184 103);
FORCEPROP 1 LAST CUSTOM_TXT_CDS <CON_PAGE_NUM> OF <CON_TOTAL_PAGES>
J 0
(-446 18);
DISPLAY 0.978723 (-446 18);
FORCEPROP 1 LAST Q_DEPT BU9
J 1
(-3763 49);
DISPLAY 1.957447 (-3763 49);
PAINT GREEN (-3763 49);
FORCEPROP 1 LAST Q_TITLE CPU1 PCIE P0/P1
J 0
(-9300 50);
DISPLAY 2.446809 (-9300 50);
PAINT GREEN (-9300 50);
FORCEPROP 2 LAST CDS_LIB pure_quanta
J 0
(0 0);
DISPLAY INVISIBLE (0 0);
FORCEPROP 1 LAST CDS_LMAN_SYM_OUTLINE -9475,6775,100,-125
J 0
(0 0);
DISPLAY 0.468085 (0 0);
PAINT GREEN (0 0);
DISPLAY INVISIBLE (0 0);
FORCEPROP 2 LAST PAGE_BORDER TRUE
J 0
(-7890 5250);
DISPLAY 0.638298 (-7890 5250);
PAINT PINK (-7890 5250);
DISPLAY INVISIBLE (-7890 5250);
FORCEPROP 1 LAST COMMENT_BODY TRUE
J 0
(12 -13);
DISPLAY 0.978723 (12 -13);
PAINT GREEN (12 -13);
DISPLAY INVISIBLE (12 -13);
FORCEPROP 2 LAST CDS_XR_PAGE_TITLE CR-51 : @T6G_MB_LIB.T6G(SCH_1):PAGE51
J 0
(-7890 5250);
DISPLAY 0.638298 (-7890 5250);
PAINT PINK (-7890 5250);
DISPLAY INVISIBLE (-7890 5250);
WIRE 17 -1 (-2750 5225)(-2750 5125);
WIRE 17 -1 (-2750 5325)(-2750 5225);
WIRE 17 -1 (-2750 5125)(-2750 5025);
WIRE 17 -1 (-2750 5025)(-2750 4925);
WIRE 17 -1 (-2750 5425)(-2750 5325);
WIRE 17 -1 (-2750 5525)(-2750 5425);
WIRE 17 -1 (-2750 4925)(-2750 4825);
WIRE 17 -1 (-2750 4825)(-2750 4725);
WIRE 17 -1 (-2750 5725)(-2750 5525);
WIRE 17 -1 (-2750 5725)(-1875 5725);
FORCEPROP 2 LAST SIG_NAME P5E_CPU1_P0_TX_DN<0:15>
J 0
(-2710 5735);
DISPLAY 0.489362 (-2710 5735);
WIRE 17 -1 (-2750 4725)(-2750 4625);
WIRE 17 -1 (-2750 4625)(-2750 4525);
WIRE 17 -1 (-2750 4525)(-2750 4425);
WIRE 17 -1 (-2750 4425)(-2750 4325);
WIRE 17 -1 (-2750 4325)(-2750 4225);
WIRE 17 -1 (-2750 4225)(-2750 4125);
WIRE 17 -1 (-2750 4125)(-2750 4025);
WIRE 17 -1 (-2900 5175)(-2900 5075);
WIRE 17 -1 (-2900 5275)(-2900 5175);
WIRE 17 -1 (-2900 5075)(-2900 4975);
WIRE 17 -1 (-2900 4975)(-2900 4875);
WIRE 17 -1 (-2900 5375)(-2900 5275);
WIRE 17 -1 (-2900 5475)(-2900 5375);
WIRE 17 -1 (-2900 4875)(-2900 4775);
WIRE 17 -1 (-2900 4775)(-2900 4675);
WIRE 17 -1 (-2900 5575)(-2900 5475);
WIRE 17 -1 (-2900 5775)(-2900 5575);
WIRE 17 -1 (-2900 4675)(-2900 4575);
WIRE 17 -1 (-2900 4575)(-2900 4475);
WIRE 17 -1 (-2900 5775)(-1875 5775);
FORCEPROP 2 LAST SIG_NAME P5E_CPU1_P0_TX_DP<0:15>
J 0
(-2710 5785);
DISPLAY 0.489362 (-2710 5785);
WIRE 17 -1 (-2900 4475)(-2900 4375);
WIRE 17 -1 (-2900 4375)(-2900 4275);
WIRE 17 -1 (-2900 4275)(-2900 4175);
WIRE 17 -1 (-2900 4175)(-2900 4075);
WIRE 17 -1 (-2825 2075)(-2825 1975);
WIRE 17 -1 (-2825 2175)(-2825 2075);
WIRE 17 -1 (-2825 1975)(-2825 1875);
WIRE 17 -1 (-2825 1875)(-2825 1775);
WIRE 17 -1 (-2825 2275)(-2825 2175);
WIRE 17 -1 (-2825 2375)(-2825 2275);
WIRE 17 -1 (-2825 1775)(-2825 1675);
WIRE 17 -1 (-2825 1675)(-2825 1575);
WIRE 17 -1 (-2825 2475)(-2825 2375);
WIRE 17 -1 (-2825 2575)(-2825 2475);
WIRE 17 -1 (-2825 1575)(-2825 1475);
WIRE 17 -1 (-2825 1475)(-2825 1375);
WIRE 17 -1 (-2825 2675)(-2825 2575);
WIRE 17 -1 (-2825 2775)(-2825 2675);
WIRE 17 -1 (-2825 2875)(-2825 2775);
WIRE 17 -1 (-2825 3075)(-2825 2875);
WIRE 17 -1 (-2825 3075)(-1950 3075);
FORCEPROP 2 LAST SIG_NAME P5E_CPU1_P1_TX_DN<15:0>
J 0
(-2635 3085);
DISPLAY 0.489362 (-2635 3085);
WIRE 17 -1 (-2975 2925)(-2975 2825);
WIRE 17 -1 (-2975 3125)(-2975 2925);
WIRE 17 -1 (-2975 2825)(-2975 2725);
WIRE 17 -1 (-2975 2725)(-2975 2625);
WIRE 17 -1 (-2975 3125)(-1950 3125);
FORCEPROP 2 LAST SIG_NAME P5E_CPU1_P1_TX_DP<15:0>
J 0
(-2635 3135);
DISPLAY 0.489362 (-2635 3135);
WIRE 17 -1 (-2975 2625)(-2975 2525);
WIRE 17 -1 (-2975 2525)(-2975 2425);
WIRE 17 -1 (-2975 2425)(-2975 2325);
WIRE 17 -1 (-2975 2325)(-2975 2225);
WIRE 17 -1 (-2975 2225)(-2975 2125);
WIRE 17 -1 (-2975 2125)(-2975 2025);
WIRE 17 -1 (-2975 2025)(-2975 1925);
WIRE 17 -1 (-2975 1925)(-2975 1825);
WIRE 17 -1 (-2975 1825)(-2975 1725);
WIRE 17 -1 (-2975 1725)(-2975 1625);
WIRE 17 -1 (-2975 1625)(-2975 1525);
WIRE 17 -1 (-2975 1525)(-2975 1425);
WIRE 17 -1 (-6650 5425)(-6650 5525);
WIRE 17 -1 (-6650 5325)(-6650 5425);
WIRE 17 -1 (-6650 5525)(-6650 5725);
WIRE 17 -1 (-6650 5725)(-7500 5725);
FORCEPROP 2 LAST SIG_NAME P5E_CPU1_P0_RX_DP<0:15>
J 0
(-7460 5735);
DISPLAY 0.489362 (-7460 5735);
WIRE 17 -1 (-6500 5375)(-6500 5475);
WIRE 17 -1 (-6500 5275)(-6500 5375);
WIRE 17 -1 (-6500 5475)(-6500 5575);
WIRE 17 -1 (-6500 5575)(-6500 5775);
WIRE 17 -1 (-6500 5175)(-6500 5275);
WIRE 17 -1 (-6500 5075)(-6500 5175);
WIRE 17 -1 (-6500 5775)(-7500 5775);
FORCEPROP 2 LAST SIG_NAME P5E_CPU1_P0_RX_DN<0:15>
J 0
(-7460 5785);
DISPLAY 0.489362 (-7460 5785);
WIRE 17 -1 (-6500 4875)(-6500 4775);
WIRE 17 -1 (-6500 4875)(-6500 4975);
WIRE 17 -1 (-6500 4675)(-6500 4775);
WIRE 17 -1 (-6500 4575)(-6500 4675);
WIRE 17 -1 (-6500 4975)(-6500 5075);
WIRE 17 -1 (-6500 4475)(-6500 4575);
WIRE 17 -1 (-6500 4375)(-6500 4475);
WIRE 17 -1 (-6500 4275)(-6500 4375);
WIRE 17 -1 (-6500 4175)(-6500 4275);
WIRE 17 -1 (-6500 4075)(-6500 4175);
WIRE 17 -1 (-6650 5225)(-6650 5325);
WIRE 17 -1 (-6650 5125)(-6650 5225);
WIRE 17 -1 (-6650 5025)(-6650 5125);
WIRE 17 -1 (-6650 4825)(-6650 4725);
WIRE 17 -1 (-6650 4825)(-6650 4925);
WIRE 17 -1 (-6650 4625)(-6650 4725);
WIRE 17 -1 (-6650 4525)(-6650 4625);
WIRE 17 -1 (-6650 4925)(-6650 5025);
WIRE 17 -1 (-6650 4425)(-6650 4525);
WIRE 17 -1 (-6650 4325)(-6650 4425);
WIRE 17 -1 (-6650 4225)(-6650 4325);
WIRE 17 -1 (-6650 4125)(-6650 4225);
WIRE 17 -1 (-6650 4025)(-6650 4125);
WIRE 17 -1 (-6500 2025)(-6500 2125);
WIRE 17 -1 (-6500 1925)(-6500 2025);
WIRE 17 -1 (-6500 2125)(-6500 2225);
WIRE 17 -1 (-6500 2225)(-6500 2325);
WIRE 17 -1 (-6500 1825)(-6500 1925);
WIRE 17 -1 (-6500 1725)(-6500 1825);
WIRE 17 -1 (-6500 2325)(-6500 2425);
WIRE 17 -1 (-6500 2425)(-6500 2525);
WIRE 17 -1 (-6500 1625)(-6500 1725);
WIRE 17 -1 (-6500 1525)(-6500 1625);
WIRE 17 -1 (-6500 2525)(-6500 2625);
WIRE 17 -1 (-6500 2625)(-6500 2725);
WIRE 17 -1 (-6500 1425)(-6500 1525);
WIRE 17 -1 (-6500 2725)(-6500 2825);
WIRE 17 -1 (-6500 2825)(-6500 2925);
WIRE 17 -1 (-6500 2925)(-6500 3125);
WIRE 17 -1 (-6500 3125)(-7575 3125);
FORCEPROP 2 LAST SIG_NAME P5E_CPU1_P1_RX_DP<15:0>
J 0
(-7460 3135);
DISPLAY 0.489362 (-7460 3135);
WIRE 17 -1 (-6650 1975)(-6650 2075);
WIRE 17 -1 (-6650 1875)(-6650 1975);
WIRE 17 -1 (-6650 2075)(-6650 2175);
WIRE 17 -1 (-6650 2175)(-6650 2275);
WIRE 17 -1 (-6650 1775)(-6650 1875);
WIRE 17 -1 (-6650 1675)(-6650 1775);
WIRE 17 -1 (-6650 2275)(-6650 2375);
WIRE 17 -1 (-6650 2375)(-6650 2475);
WIRE 17 -1 (-6650 1575)(-6650 1675);
WIRE 17 -1 (-6650 1475)(-6650 1575);
WIRE 17 -1 (-6650 2475)(-6650 2575);
WIRE 17 -1 (-6650 2575)(-6650 2675);
WIRE 17 -1 (-6650 1375)(-6650 1475);
WIRE 17 -1 (-6650 2675)(-6650 2775);
WIRE 17 -1 (-6650 2775)(-6650 2875);
WIRE 17 -1 (-6650 2875)(-6650 3075);
WIRE 17 -1 (-7575 3075)(-6650 3075);
FORCEPROP 2 LAST SIG_NAME P5E_CPU1_P1_RX_DN<15:0>
J 0
(-7460 3085);
DISPLAY 0.489362 (-7460 3085);
WIRE 16 -1 (-6550 2250)(-5950 2250);
WIRE 16 -1 (-6400 2300)(-5950 2300);
WIRE 16 -1 (-6400 5250)(-5950 5250);
WIRE 16 -1 (-6550 5200)(-5950 5200);
WIRE 16 -1 (-6400 5150)(-5950 5150);
WIRE 16 -1 (-6550 5100)(-5950 5100);
WIRE 16 -1 (-6550 5000)(-5950 5000);
WIRE 16 -1 (-6550 4900)(-5950 4900);
WIRE 16 -1 (-6400 4050)(-5950 4050);
WIRE 16 -1 (-6550 4000)(-5950 4000);
WIRE 16 -1 (-6550 2350)(-5950 2350);
WIRE 16 -1 (-6400 2200)(-5950 2200);
WIRE 16 -1 (-6550 2450)(-5950 2450);
WIRE 16 -1 (-6550 2550)(-5950 2550);
WIRE 16 -1 (-6400 2400)(-5950 2400);
WIRE 16 -1 (-6550 2650)(-5950 2650);
WIRE 16 -1 (-6400 2500)(-5950 2500);
WIRE 16 -1 (-6550 2750)(-5950 2750);
WIRE 16 -1 (-6400 2600)(-5950 2600);
WIRE 16 -1 (-6550 2850)(-5950 2850);
WIRE 16 -1 (-6400 2700)(-5950 2700);
WIRE 16 -1 (-6400 2800)(-5950 2800);
WIRE 16 -1 (-6400 2900)(-5950 2900);
WIRE 16 -1 (-6550 2150)(-5950 2150);
WIRE 16 -1 (-6550 1350)(-5950 1350);
WIRE 16 -1 (-6400 1400)(-5950 1400);
WIRE 16 -1 (-6550 1450)(-5950 1450);
WIRE 16 -1 (-6400 1500)(-5950 1500);
WIRE 16 -1 (-6550 1550)(-5950 1550);
WIRE 16 -1 (-6400 1600)(-5950 1600);
WIRE 16 -1 (-6550 1650)(-5950 1650);
WIRE 16 -1 (-6400 1700)(-5950 1700);
WIRE 16 -1 (-6550 1750)(-5950 1750);
WIRE 16 -1 (-6400 1800)(-5950 1800);
WIRE 16 -1 (-6550 1850)(-5950 1850);
WIRE 16 -1 (-6400 1900)(-5950 1900);
WIRE 16 -1 (-6550 1950)(-5950 1950);
WIRE 16 -1 (-6400 2000)(-5950 2000);
WIRE 16 -1 (-6550 2050)(-5950 2050);
WIRE 16 -1 (-6400 2100)(-5950 2100);
WIRE 16 -1 (-6400 4450)(-5950 4450);
WIRE 16 -1 (-6550 4400)(-5950 4400);
WIRE 16 -1 (-6550 4100)(-5950 4100);
WIRE 16 -1 (-6400 4250)(-5950 4250);
WIRE 16 -1 (-6400 4550)(-5950 4550);
WIRE 16 -1 (-6550 4600)(-5950 4600);
WIRE 16 -1 (-6550 4500)(-5950 4500);
WIRE 16 -1 (-6550 4200)(-5950 4200);
WIRE 16 -1 (-6400 4650)(-5950 4650);
WIRE 16 -1 (-6400 4350)(-5950 4350);
WIRE 16 -1 (-6550 4700)(-5950 4700);
WIRE 16 -1 (-6550 4300)(-5950 4300);
WIRE 16 -1 (-6400 4750)(-5950 4750);
WIRE 16 -1 (-6400 4150)(-5950 4150);
WIRE 16 -1 (-6400 4950)(-5950 4950);
WIRE 16 -1 (-6400 5550)(-5950 5550);
WIRE 16 -1 (-6550 5300)(-5950 5300);
WIRE 16 -1 (-6400 5050)(-5950 5050);
WIRE 16 -1 (-6400 5350)(-5950 5350);
WIRE 16 -1 (-6550 4800)(-5950 4800);
WIRE 16 -1 (-6550 5400)(-5950 5400);
WIRE 16 -1 (-6400 4850)(-5950 4850);
WIRE 16 -1 (-6400 5450)(-5950 5450);
WIRE 16 -1 (-6550 5500)(-5950 5500);
WIRE 16 -1 (-3450 1400)(-3075 1400);
WIRE 16 -1 (-3450 1500)(-3075 1500);
WIRE 16 -1 (-3450 1600)(-3075 1600);
WIRE 16 -1 (-3450 1700)(-3075 1700);
WIRE 16 -1 (-3450 1800)(-3075 1800);
WIRE 16 -1 (-3450 1900)(-3075 1900);
WIRE 16 -1 (-3450 2000)(-3075 2000);
WIRE 16 -1 (-3450 1350)(-2925 1350);
WIRE 16 -1 (-3450 1450)(-2925 1450);
WIRE 16 -1 (-3450 1550)(-2925 1550);
WIRE 16 -1 (-3450 1650)(-2925 1650);
WIRE 16 -1 (-3450 1750)(-2925 1750);
WIRE 16 -1 (-3450 1850)(-2925 1850);
WIRE 16 -1 (-3450 1950)(-2925 1950);
WIRE 16 -1 (-3450 2200)(-3075 2200);
WIRE 16 -1 (-3450 2300)(-3075 2300);
WIRE 16 -1 (-3450 2400)(-3075 2400);
WIRE 16 -1 (-3450 2500)(-3075 2500);
WIRE 16 -1 (-3450 2100)(-3075 2100);
WIRE 16 -1 (-3450 2600)(-3075 2600);
WIRE 16 -1 (-3450 2700)(-3075 2700);
WIRE 16 -1 (-3450 2800)(-3075 2800);
WIRE 16 -1 (-3450 2900)(-3075 2900);
WIRE 16 -1 (-3450 4050)(-3000 4050);
WIRE 16 -1 (-3450 4000)(-2850 4000);
WIRE 16 -1 (-3450 2150)(-2925 2150);
WIRE 16 -1 (-3450 2250)(-2925 2250);
WIRE 16 -1 (-3450 2350)(-2925 2350);
WIRE 16 -1 (-3450 2450)(-2925 2450);
WIRE 16 -1 (-3450 2550)(-2925 2550);
WIRE 16 -1 (-3450 2650)(-2925 2650);
WIRE 16 -1 (-3450 2750)(-2925 2750);
WIRE 16 -1 (-3450 2850)(-2925 2850);
WIRE 16 -1 (-3450 2050)(-2925 2050);
WIRE 16 -1 (-3450 4350)(-3000 4350);
WIRE 16 -1 (-3450 4600)(-2850 4600);
WIRE 16 -1 (-3450 4300)(-2850 4300);
WIRE 16 -1 (-3450 4450)(-3000 4450);
WIRE 16 -1 (-3450 4150)(-3000 4150);
WIRE 16 -1 (-3450 4650)(-3000 4650);
WIRE 16 -1 (-3450 4100)(-2850 4100);
WIRE 16 -1 (-3450 4700)(-2850 4700);
WIRE 16 -1 (-3450 4400)(-2850 4400);
WIRE 16 -1 (-3450 4250)(-3000 4250);
WIRE 16 -1 (-3450 4550)(-3000 4550);
WIRE 16 -1 (-3450 4750)(-3000 4750);
WIRE 16 -1 (-3450 4500)(-2850 4500);
WIRE 16 -1 (-3450 4200)(-2850 4200);
WIRE 16 -1 (-3450 5250)(-3000 5250);
WIRE 16 -1 (-3450 4950)(-3000 4950);
WIRE 16 -1 (-3450 5550)(-3000 5550);
WIRE 16 -1 (-3450 5000)(-2850 5000);
WIRE 16 -1 (-3450 5300)(-2850 5300);
WIRE 16 -1 (-3450 5350)(-3000 5350);
WIRE 16 -1 (-3450 5050)(-3000 5050);
WIRE 16 -1 (-3450 5400)(-2850 5400);
WIRE 16 -1 (-3450 4800)(-2850 4800);
WIRE 16 -1 (-3450 5100)(-2850 5100);
WIRE 16 -1 (-3450 4850)(-3000 4850);
WIRE 16 -1 (-3450 5450)(-3000 5450);
WIRE 16 -1 (-3450 5150)(-3000 5150);
WIRE 16 -1 (-3450 4900)(-2850 4900);
WIRE 16 -1 (-3450 5500)(-2850 5500);
WIRE 16 -1 (-3450 5200)(-2850 5200);
FORCENOTE
CPU1 P1[15:0] TO SLOT#2
(-2500 1925) 0;
DISPLAY LEFT (-2500 1925);
DISPLAY 2.000000 (-2500 1925);
FORCENOTE
CPU1 P0[15:0] TO SLOT#3
(-2500 4450) 0;
DISPLAY LEFT (-2500 4450);
DISPLAY 2.000000 (-2500 4450);
FORCENOTE
(LANE REVERSAL/RX PN SWAP)
(-2500 4275) 0;
DISPLAY LEFT (-2500 4275);
DISPLAY 2.000000 (-2500 4275);
QUIT
